(kicad_sch (version 20230121) (generator eeschema)

  (paper "A3")

  (title_block
    (title "ECP5 - Datacenter Secure Control Module (DC-SCM)")
    (date "2024-07-15")
    (rev "1.2.1")
  )

  (junction (at 87.63 74.93) (diameter 0) (color 0 0 0 0)
  )
  (junction (at 96.52 95.25) (diameter 0) (color 0 0 0 0)
  )
  (junction (at 107.95 138.43) (diameter 0) (color 0 0 0 0)
  )
  (junction (at 62.23 173.99) (diameter 0) (color 0 0 0 0)
  )
  (junction (at 107.95 128.27) (diameter 0) (color 0 0 0 0)
  )
  (junction (at 93.98 66.04) (diameter 0) (color 0 0 0 0)
  )
  (junction (at 88.9 128.27) (diameter 0) (color 0 0 0 0)
  )
  (junction (at 320.04 119.38) (diameter 0) (color 0 0 0 0)
  )
  (junction (at 106.68 74.93) (diameter 0) (color 0 0 0 0)
  )
  (junction (at 121.92 95.25) (diameter 0) (color 0 0 0 0)
  )
  (junction (at 323.85 146.05) (diameter 0) (color 0 0 0 0)
  )
  (junction (at 63.5 138.43) (diameter 0) (color 0 0 0 0)
  )
  (junction (at 246.38 81.28) (diameter 0) (color 0 0 0 0)
  )
  (junction (at 132.08 74.93) (diameter 0) (color 0 0 0 0)
  )
  (junction (at 68.58 173.99) (diameter 0) (color 0 0 0 0)
  )
  (junction (at 106.68 165.1) (diameter 0) (color 0 0 0 0)
  )
  (junction (at 100.33 66.04) (diameter 0) (color 0 0 0 0)
  )
  (junction (at 132.08 66.04) (diameter 0) (color 0 0 0 0)
  )
  (junction (at 115.57 105.41) (diameter 0) (color 0 0 0 0)
  )
  (junction (at 119.38 74.93) (diameter 0) (color 0 0 0 0)
  )
  (junction (at 101.6 128.27) (diameter 0) (color 0 0 0 0)
  )
  (junction (at 100.33 173.99) (diameter 0) (color 0 0 0 0)
  )
  (junction (at 81.28 173.99) (diameter 0) (color 0 0 0 0)
  )
  (junction (at 327.66 129.54) (diameter 0) (color 0 0 0 0)
  )
  (junction (at 125.73 74.93) (diameter 0) (color 0 0 0 0)
  )
  (junction (at 30.48 74.93) (diameter 0) (color 0 0 0 0)
  )
  (junction (at 318.77 93.98) (diameter 0) (color 0 0 0 0)
  )
  (junction (at 55.88 74.93) (diameter 0) (color 0 0 0 0)
  )
  (junction (at 77.47 105.41) (diameter 0) (color 0 0 0 0)
  )
  (junction (at 71.12 105.41) (diameter 0) (color 0 0 0 0)
  )
  (junction (at 30.48 66.04) (diameter 0) (color 0 0 0 0)
  )
  (junction (at 74.93 74.93) (diameter 0) (color 0 0 0 0)
  )
  (junction (at 125.73 173.99) (diameter 0) (color 0 0 0 0)
  )
  (junction (at 74.93 66.04) (diameter 0) (color 0 0 0 0)
  )
  (junction (at 36.83 66.04) (diameter 0) (color 0 0 0 0)
  )
  (junction (at 71.12 95.25) (diameter 0) (color 0 0 0 0)
  )
  (junction (at 144.78 74.93) (diameter 0) (color 0 0 0 0)
  )
  (junction (at 119.38 165.1) (diameter 0) (color 0 0 0 0)
  )
  (junction (at 138.43 74.93) (diameter 0) (color 0 0 0 0)
  )
  (junction (at 68.58 66.04) (diameter 0) (color 0 0 0 0)
  )
  (junction (at 81.28 74.93) (diameter 0) (color 0 0 0 0)
  )
  (junction (at 246.38 91.44) (diameter 0) (color 0 0 0 0)
  )
  (junction (at 102.87 95.25) (diameter 0) (color 0 0 0 0)
  )
  (junction (at 43.18 66.04) (diameter 0) (color 0 0 0 0)
  )
  (junction (at 125.73 66.04) (diameter 0) (color 0 0 0 0)
  )
  (junction (at 90.17 105.41) (diameter 0) (color 0 0 0 0)
  )
  (junction (at 93.98 165.1) (diameter 0) (color 0 0 0 0)
  )
  (junction (at 69.85 128.27) (diameter 0) (color 0 0 0 0)
  )
  (junction (at 246.38 86.36) (diameter 0) (color 0 0 0 0)
  )
  (junction (at 49.53 66.04) (diameter 0) (color 0 0 0 0)
  )
  (junction (at 113.03 173.99) (diameter 0) (color 0 0 0 0)
  )
  (junction (at 43.18 74.93) (diameter 0) (color 0 0 0 0)
  )
  (junction (at 100.33 74.93) (diameter 0) (color 0 0 0 0)
  )
  (junction (at 101.6 138.43) (diameter 0) (color 0 0 0 0)
  )
  (junction (at 83.82 105.41) (diameter 0) (color 0 0 0 0)
  )
  (junction (at 74.93 165.1) (diameter 0) (color 0 0 0 0)
  )
  (junction (at 76.2 128.27) (diameter 0) (color 0 0 0 0)
  )
  (junction (at 62.23 66.04) (diameter 0) (color 0 0 0 0)
  )
  (junction (at 119.38 173.99) (diameter 0) (color 0 0 0 0)
  )
  (junction (at 200.66 87.63) (diameter 0) (color 0 0 0 0)
  )
  (junction (at 69.85 138.43) (diameter 0) (color 0 0 0 0)
  )
  (junction (at 62.23 165.1) (diameter 0) (color 0 0 0 0)
  )
  (junction (at 109.22 95.25) (diameter 0) (color 0 0 0 0)
  )
  (junction (at 151.13 74.93) (diameter 0) (color 0 0 0 0)
  )
  (junction (at 100.33 165.1) (diameter 0) (color 0 0 0 0)
  )
  (junction (at 87.63 165.1) (diameter 0) (color 0 0 0 0)
  )
  (junction (at 119.38 66.04) (diameter 0) (color 0 0 0 0)
  )
  (junction (at 312.42 119.38) (diameter 0) (color 0 0 0 0)
  )
  (junction (at 113.03 66.04) (diameter 0) (color 0 0 0 0)
  )
  (junction (at 90.17 95.25) (diameter 0) (color 0 0 0 0)
  )
  (junction (at 82.55 128.27) (diameter 0) (color 0 0 0 0)
  )
  (junction (at 326.39 93.98) (diameter 0) (color 0 0 0 0)
  )
  (junction (at 144.78 66.04) (diameter 0) (color 0 0 0 0)
  )
  (junction (at 81.28 165.1) (diameter 0) (color 0 0 0 0)
  )
  (junction (at 106.68 66.04) (diameter 0) (color 0 0 0 0)
  )
  (junction (at 325.12 81.28) (diameter 0) (color 0 0 0 0)
  )
  (junction (at 36.83 74.93) (diameter 0) (color 0 0 0 0)
  )
  (junction (at 125.73 165.1) (diameter 0) (color 0 0 0 0)
  )
  (junction (at 109.22 105.41) (diameter 0) (color 0 0 0 0)
  )
  (junction (at 55.88 66.04) (diameter 0) (color 0 0 0 0)
  )
  (junction (at 332.74 102.87) (diameter 0) (color 0 0 0 0)
  )
  (junction (at 96.52 105.41) (diameter 0) (color 0 0 0 0)
  )
  (junction (at 83.82 95.25) (diameter 0) (color 0 0 0 0)
  )
  (junction (at 316.23 72.39) (diameter 0) (color 0 0 0 0)
  )
  (junction (at 332.74 93.98) (diameter 0) (color 0 0 0 0)
  )
  (junction (at 93.98 173.99) (diameter 0) (color 0 0 0 0)
  )
  (junction (at 87.63 173.99) (diameter 0) (color 0 0 0 0)
  )
  (junction (at 323.85 154.94) (diameter 0) (color 0 0 0 0)
  )
  (junction (at 74.93 173.99) (diameter 0) (color 0 0 0 0)
  )
  (junction (at 82.55 138.43) (diameter 0) (color 0 0 0 0)
  )
  (junction (at 68.58 165.1) (diameter 0) (color 0 0 0 0)
  )
  (junction (at 309.88 146.05) (diameter 0) (color 0 0 0 0)
  )
  (junction (at 95.25 128.27) (diameter 0) (color 0 0 0 0)
  )
  (junction (at 325.12 72.39) (diameter 0) (color 0 0 0 0)
  )
  (junction (at 93.98 74.93) (diameter 0) (color 0 0 0 0)
  )
  (junction (at 332.74 81.28) (diameter 0) (color 0 0 0 0)
  )
  (junction (at 317.5 146.05) (diameter 0) (color 0 0 0 0)
  )
  (junction (at 62.23 74.93) (diameter 0) (color 0 0 0 0)
  )
  (junction (at 327.66 119.38) (diameter 0) (color 0 0 0 0)
  )
  (junction (at 246.38 76.2) (diameter 0) (color 0 0 0 0)
  )
  (junction (at 332.74 72.39) (diameter 0) (color 0 0 0 0)
  )
  (junction (at 200.66 85.09) (diameter 0) (color 0 0 0 0)
  )
  (junction (at 132.08 165.1) (diameter 0) (color 0 0 0 0)
  )
  (junction (at 320.04 129.54) (diameter 0) (color 0 0 0 0)
  )
  (junction (at 77.47 95.25) (diameter 0) (color 0 0 0 0)
  )
  (junction (at 68.58 74.93) (diameter 0) (color 0 0 0 0)
  )
  (junction (at 113.03 74.93) (diameter 0) (color 0 0 0 0)
  )
  (junction (at 138.43 66.04) (diameter 0) (color 0 0 0 0)
  )
  (junction (at 88.9 138.43) (diameter 0) (color 0 0 0 0)
  )
  (junction (at 157.48 66.04) (diameter 0) (color 0 0 0 0)
  )
  (junction (at 49.53 74.93) (diameter 0) (color 0 0 0 0)
  )
  (junction (at 113.03 165.1) (diameter 0) (color 0 0 0 0)
  )
  (junction (at 102.87 105.41) (diameter 0) (color 0 0 0 0)
  )
  (junction (at 151.13 66.04) (diameter 0) (color 0 0 0 0)
  )
  (junction (at 63.5 128.27) (diameter 0) (color 0 0 0 0)
  )
  (junction (at 95.25 138.43) (diameter 0) (color 0 0 0 0)
  )
  (junction (at 87.63 66.04) (diameter 0) (color 0 0 0 0)
  )
  (junction (at 81.28 66.04) (diameter 0) (color 0 0 0 0)
  )
  (junction (at 326.39 102.87) (diameter 0) (color 0 0 0 0)
  )
  (junction (at 114.3 128.27) (diameter 0) (color 0 0 0 0)
  )
  (junction (at 115.57 95.25) (diameter 0) (color 0 0 0 0)
  )
  (junction (at 106.68 173.99) (diameter 0) (color 0 0 0 0)
  )
  (junction (at 317.5 154.94) (diameter 0) (color 0 0 0 0)
  )
  (junction (at 76.2 138.43) (diameter 0) (color 0 0 0 0)
  )

  (wire (pts (xy 68.58 74.93) (xy 62.23 74.93))
    (stroke (width 0) (type default))
  )
  (wire (pts (xy 64.77 105.41) (xy 71.12 105.41))
    (stroke (width 0) (type default))
  )
  (wire (pts (xy 90.17 102.87) (xy 90.17 105.41))
    (stroke (width 0) (type default))
  )
  (wire (pts (xy 81.28 73.66) (xy 81.28 74.93))
    (stroke (width 0) (type default))
  )
  (wire (pts (xy 320.04 129.54) (xy 320.04 127))
    (stroke (width 0) (type default))
  )
  (wire (pts (xy 240.03 91.44) (xy 246.38 91.44))
    (stroke (width 0) (type default))
  )
  (wire (pts (xy 240.03 81.28) (xy 246.38 81.28))
    (stroke (width 0) (type default))
  )
  (wire (pts (xy 93.98 74.93) (xy 87.63 74.93))
    (stroke (width 0) (type default))
  )
  (wire (pts (xy 114.3 128.27) (xy 107.95 128.27))
    (stroke (width 0) (type default))
  )
  (wire (pts (xy 119.38 165.1) (xy 113.03 165.1))
    (stroke (width 0) (type default))
  )
  (wire (pts (xy 355.6 119.38) (xy 327.66 119.38))
    (stroke (width 0) (type default))
  )
  (wire (pts (xy 87.63 172.72) (xy 87.63 173.99))
    (stroke (width 0) (type default))
  )
  (wire (pts (xy 344.17 93.98) (xy 332.74 93.98))
    (stroke (width 0) (type default))
  )
  (wire (pts (xy 246.38 86.36) (xy 273.05 86.36))
    (stroke (width 0) (type default))
  )
  (wire (pts (xy 41.91 95.25) (xy 71.12 95.25))
    (stroke (width 0) (type default))
  )
  (wire (pts (xy 62.23 163.83) (xy 62.23 165.1))
    (stroke (width 0) (type default))
  )
  (wire (pts (xy 100.33 165.1) (xy 93.98 165.1))
    (stroke (width 0) (type default))
  )
  (wire (pts (xy 132.08 74.93) (xy 125.73 74.93))
    (stroke (width 0) (type default))
  )
  (wire (pts (xy 106.68 165.1) (xy 100.33 165.1))
    (stroke (width 0) (type default))
  )
  (wire (pts (xy 106.68 165.1) (xy 106.68 167.64))
    (stroke (width 0) (type default))
  )
  (wire (pts (xy 317.5 153.67) (xy 317.5 154.94))
    (stroke (width 0) (type default))
  )
  (wire (pts (xy 93.98 173.99) (xy 87.63 173.99))
    (stroke (width 0) (type default))
  )
  (wire (pts (xy 36.83 74.93) (xy 30.48 74.93))
    (stroke (width 0) (type default))
  )
  (wire (pts (xy 318.77 93.98) (xy 318.77 96.52))
    (stroke (width 0) (type default))
  )
  (wire (pts (xy 100.33 165.1) (xy 100.33 167.64))
    (stroke (width 0) (type default))
  )
  (wire (pts (xy 71.12 95.25) (xy 77.47 95.25))
    (stroke (width 0) (type default))
  )
  (wire (pts (xy 119.38 66.04) (xy 119.38 68.58))
    (stroke (width 0) (type default))
  )
  (wire (pts (xy 323.85 146.05) (xy 323.85 148.59))
    (stroke (width 0) (type default))
  )
  (wire (pts (xy 100.33 74.93) (xy 93.98 74.93))
    (stroke (width 0) (type default))
  )
  (wire (pts (xy 102.87 105.41) (xy 109.22 105.41))
    (stroke (width 0) (type default))
  )
  (wire (pts (xy 157.48 66.04) (xy 157.48 68.58))
    (stroke (width 0) (type default))
  )
  (wire (pts (xy 332.74 93.98) (xy 326.39 93.98))
    (stroke (width 0) (type default))
  )
  (wire (pts (xy 77.47 95.25) (xy 77.47 97.79))
    (stroke (width 0) (type default))
  )
  (wire (pts (xy 317.5 146.05) (xy 309.88 146.05))
    (stroke (width 0) (type default))
  )
  (wire (pts (xy 332.74 101.6) (xy 332.74 102.87))
    (stroke (width 0) (type default))
  )
  (wire (pts (xy 74.93 66.04) (xy 74.93 68.58))
    (stroke (width 0) (type default))
  )
  (wire (pts (xy 63.5 130.81) (xy 63.5 128.27))
    (stroke (width 0) (type default))
  )
  (wire (pts (xy 87.63 73.66) (xy 87.63 74.93))
    (stroke (width 0) (type default))
  )
  (wire (pts (xy 242.57 116.84) (xy 242.57 123.19))
    (stroke (width 0) (type default))
  )
  (wire (pts (xy 138.43 73.66) (xy 138.43 74.93))
    (stroke (width 0) (type default))
  )
  (wire (pts (xy 151.13 74.93) (xy 144.78 74.93))
    (stroke (width 0) (type default))
  )
  (wire (pts (xy 83.82 95.25) (xy 90.17 95.25))
    (stroke (width 0) (type default))
  )
  (wire (pts (xy 81.28 74.93) (xy 74.93 74.93))
    (stroke (width 0) (type default))
  )
  (wire (pts (xy 62.23 74.93) (xy 55.88 74.93))
    (stroke (width 0) (type default))
  )
  (wire (pts (xy 68.58 173.99) (xy 62.23 173.99))
    (stroke (width 0) (type default))
  )
  (wire (pts (xy 93.98 73.66) (xy 93.98 74.93))
    (stroke (width 0) (type default))
  )
  (wire (pts (xy 76.2 138.43) (xy 69.85 138.43))
    (stroke (width 0) (type default))
  )
  (wire (pts (xy 163.83 76.2) (xy 201.93 76.2))
    (stroke (width 0) (type default))
  )
  (wire (pts (xy 327.66 129.54) (xy 320.04 129.54))
    (stroke (width 0) (type default))
  )
  (wire (pts (xy 200.66 85.09) (xy 201.93 85.09))
    (stroke (width 0) (type default))
  )
  (wire (pts (xy 138.43 66.04) (xy 132.08 66.04))
    (stroke (width 0) (type default))
  )
  (wire (pts (xy 62.23 172.72) (xy 62.23 173.99))
    (stroke (width 0) (type default))
  )
  (wire (pts (xy 95.25 128.27) (xy 88.9 128.27))
    (stroke (width 0) (type default))
  )
  (wire (pts (xy 62.23 173.99) (xy 62.23 176.53))
    (stroke (width 0) (type default))
  )
  (wire (pts (xy 46.99 128.27) (xy 29.21 128.27))
    (stroke (width 0) (type default))
  )
  (wire (pts (xy 151.13 73.66) (xy 151.13 74.93))
    (stroke (width 0) (type default))
  )
  (wire (pts (xy 83.82 105.41) (xy 90.17 105.41))
    (stroke (width 0) (type default))
  )
  (wire (pts (xy 68.58 66.04) (xy 62.23 66.04))
    (stroke (width 0) (type default))
  )
  (wire (pts (xy 87.63 173.99) (xy 81.28 173.99))
    (stroke (width 0) (type default))
  )
  (wire (pts (xy 71.12 102.87) (xy 71.12 105.41))
    (stroke (width 0) (type default))
  )
  (wire (pts (xy 325.12 81.28) (xy 316.23 81.28))
    (stroke (width 0) (type default))
  )
  (wire (pts (xy 327.66 129.54) (xy 327.66 132.08))
    (stroke (width 0) (type default))
  )
  (wire (pts (xy 312.42 129.54) (xy 312.42 127))
    (stroke (width 0) (type default))
  )
  (wire (pts (xy 81.28 165.1) (xy 74.93 165.1))
    (stroke (width 0) (type default))
  )
  (wire (pts (xy 106.68 73.66) (xy 106.68 74.93))
    (stroke (width 0) (type default))
  )
  (wire (pts (xy 90.17 95.25) (xy 96.52 95.25))
    (stroke (width 0) (type default))
  )
  (wire (pts (xy 100.33 66.04) (xy 100.33 68.58))
    (stroke (width 0) (type default))
  )
  (wire (pts (xy 68.58 165.1) (xy 62.23 165.1))
    (stroke (width 0) (type default))
  )
  (wire (pts (xy 332.74 81.28) (xy 332.74 78.74))
    (stroke (width 0) (type default))
  )
  (wire (pts (xy 292.1 76.2) (xy 292.1 72.39))
    (stroke (width 0) (type default))
  )
  (wire (pts (xy 332.74 81.28) (xy 332.74 82.55))
    (stroke (width 0) (type default))
  )
  (wire (pts (xy 55.88 73.66) (xy 55.88 74.93))
    (stroke (width 0) (type default))
  )
  (wire (pts (xy 96.52 102.87) (xy 96.52 105.41))
    (stroke (width 0) (type default))
  )
  (wire (pts (xy 240.03 93.98) (xy 246.38 93.98))
    (stroke (width 0) (type default))
  )
  (wire (pts (xy 114.3 128.27) (xy 167.64 128.27))
    (stroke (width 0) (type default))
  )
  (wire (pts (xy 101.6 130.81) (xy 101.6 128.27))
    (stroke (width 0) (type default))
  )
  (wire (pts (xy 114.3 138.43) (xy 107.95 138.43))
    (stroke (width 0) (type default))
  )
  (wire (pts (xy 138.43 66.04) (xy 138.43 68.58))
    (stroke (width 0) (type default))
  )
  (wire (pts (xy 151.13 66.04) (xy 151.13 68.58))
    (stroke (width 0) (type default))
  )
  (wire (pts (xy 332.74 93.98) (xy 332.74 96.52))
    (stroke (width 0) (type default))
  )
  (wire (pts (xy 320.04 129.54) (xy 312.42 129.54))
    (stroke (width 0) (type default))
  )
  (wire (pts (xy 88.9 130.81) (xy 88.9 128.27))
    (stroke (width 0) (type default))
  )
  (wire (pts (xy 55.88 66.04) (xy 49.53 66.04))
    (stroke (width 0) (type default))
  )
  (wire (pts (xy 318.77 101.6) (xy 318.77 102.87))
    (stroke (width 0) (type default))
  )
  (wire (pts (xy 81.28 66.04) (xy 74.93 66.04))
    (stroke (width 0) (type default))
  )
  (wire (pts (xy 27.94 95.25) (xy 36.83 95.25))
    (stroke (width 0) (type default))
  )
  (wire (pts (xy 76.2 138.43) (xy 76.2 135.89))
    (stroke (width 0) (type default))
  )
  (wire (pts (xy 312.42 121.92) (xy 312.42 119.38))
    (stroke (width 0) (type default))
  )
  (wire (pts (xy 69.85 128.27) (xy 63.5 128.27))
    (stroke (width 0) (type default))
  )
  (wire (pts (xy 273.05 86.36) (xy 273.05 119.38))
    (stroke (width 0) (type default))
  )
  (wire (pts (xy 74.93 165.1) (xy 68.58 165.1))
    (stroke (width 0) (type default))
  )
  (wire (pts (xy 181.61 165.1) (xy 181.61 85.09))
    (stroke (width 0) (type default))
  )
  (wire (pts (xy 109.22 95.25) (xy 115.57 95.25))
    (stroke (width 0) (type default))
  )
  (wire (pts (xy 87.63 66.04) (xy 87.63 68.58))
    (stroke (width 0) (type default))
  )
  (wire (pts (xy 93.98 165.1) (xy 93.98 167.64))
    (stroke (width 0) (type default))
  )
  (wire (pts (xy 113.03 173.99) (xy 106.68 173.99))
    (stroke (width 0) (type default))
  )
  (wire (pts (xy 119.38 172.72) (xy 119.38 173.99))
    (stroke (width 0) (type default))
  )
  (wire (pts (xy 106.68 172.72) (xy 106.68 173.99))
    (stroke (width 0) (type default))
  )
  (wire (pts (xy 68.58 66.04) (xy 68.58 68.58))
    (stroke (width 0) (type default))
  )
  (wire (pts (xy 372.11 119.38) (xy 360.68 119.38))
    (stroke (width 0) (type default))
  )
  (wire (pts (xy 138.43 74.93) (xy 132.08 74.93))
    (stroke (width 0) (type default))
  )
  (wire (pts (xy 246.38 93.98) (xy 246.38 91.44))
    (stroke (width 0) (type default))
  )
  (wire (pts (xy 71.12 95.25) (xy 71.12 97.79))
    (stroke (width 0) (type default))
  )
  (wire (pts (xy 142.24 95.25) (xy 142.24 78.74))
    (stroke (width 0) (type default))
  )
  (wire (pts (xy 113.03 74.93) (xy 106.68 74.93))
    (stroke (width 0) (type default))
  )
  (wire (pts (xy 106.68 173.99) (xy 100.33 173.99))
    (stroke (width 0) (type default))
  )
  (wire (pts (xy 323.85 154.94) (xy 323.85 157.48))
    (stroke (width 0) (type default))
  )
  (wire (pts (xy 200.66 90.17) (xy 200.66 87.63))
    (stroke (width 0) (type default))
  )
  (wire (pts (xy 132.08 172.72) (xy 132.08 173.99))
    (stroke (width 0) (type default))
  )
  (wire (pts (xy 49.53 74.93) (xy 43.18 74.93))
    (stroke (width 0) (type default))
  )
  (wire (pts (xy 88.9 138.43) (xy 82.55 138.43))
    (stroke (width 0) (type default))
  )
  (wire (pts (xy 142.24 78.74) (xy 201.93 78.74))
    (stroke (width 0) (type default))
  )
  (wire (pts (xy 157.48 74.93) (xy 151.13 74.93))
    (stroke (width 0) (type default))
  )
  (wire (pts (xy 114.3 138.43) (xy 114.3 135.89))
    (stroke (width 0) (type default))
  )
  (wire (pts (xy 113.03 165.1) (xy 113.03 167.64))
    (stroke (width 0) (type default))
  )
  (wire (pts (xy 318.77 102.87) (xy 326.39 102.87))
    (stroke (width 0) (type default))
  )
  (wire (pts (xy 87.63 74.93) (xy 81.28 74.93))
    (stroke (width 0) (type default))
  )
  (wire (pts (xy 76.2 130.81) (xy 76.2 128.27))
    (stroke (width 0) (type default))
  )
  (wire (pts (xy 82.55 128.27) (xy 76.2 128.27))
    (stroke (width 0) (type default))
  )
  (wire (pts (xy 93.98 66.04) (xy 87.63 66.04))
    (stroke (width 0) (type default))
  )
  (wire (pts (xy 246.38 88.9) (xy 246.38 86.36))
    (stroke (width 0) (type default))
  )
  (wire (pts (xy 36.83 66.04) (xy 30.48 66.04))
    (stroke (width 0) (type default))
  )
  (wire (pts (xy 309.88 146.05) (xy 309.88 148.59))
    (stroke (width 0) (type default))
  )
  (wire (pts (xy 36.83 66.04) (xy 36.83 68.58))
    (stroke (width 0) (type default))
  )
  (wire (pts (xy 101.6 138.43) (xy 101.6 135.89))
    (stroke (width 0) (type default))
  )
  (wire (pts (xy 62.23 165.1) (xy 41.91 165.1))
    (stroke (width 0) (type default))
  )
  (wire (pts (xy 30.48 66.04) (xy 30.48 68.58))
    (stroke (width 0) (type default))
  )
  (wire (pts (xy 49.53 66.04) (xy 43.18 66.04))
    (stroke (width 0) (type default))
  )
  (wire (pts (xy 101.6 138.43) (xy 95.25 138.43))
    (stroke (width 0) (type default))
  )
  (wire (pts (xy 55.88 66.04) (xy 55.88 68.58))
    (stroke (width 0) (type default))
  )
  (wire (pts (xy 113.03 73.66) (xy 113.03 74.93))
    (stroke (width 0) (type default))
  )
  (wire (pts (xy 119.38 74.93) (xy 113.03 74.93))
    (stroke (width 0) (type default))
  )
  (wire (pts (xy 81.28 172.72) (xy 81.28 173.99))
    (stroke (width 0) (type default))
  )
  (wire (pts (xy 320.04 119.38) (xy 312.42 119.38))
    (stroke (width 0) (type default))
  )
  (wire (pts (xy 119.38 173.99) (xy 113.03 173.99))
    (stroke (width 0) (type default))
  )
  (wire (pts (xy 81.28 173.99) (xy 74.93 173.99))
    (stroke (width 0) (type default))
  )
  (wire (pts (xy 132.08 165.1) (xy 132.08 167.64))
    (stroke (width 0) (type default))
  )
  (wire (pts (xy 100.33 73.66) (xy 100.33 74.93))
    (stroke (width 0) (type default))
  )
  (wire (pts (xy 332.74 73.66) (xy 332.74 72.39))
    (stroke (width 0) (type default))
  )
  (wire (pts (xy 64.77 105.41) (xy 64.77 107.95))
    (stroke (width 0) (type default))
  )
  (wire (pts (xy 323.85 144.78) (xy 323.85 146.05))
    (stroke (width 0) (type default))
  )
  (wire (pts (xy 246.38 83.82) (xy 246.38 81.28))
    (stroke (width 0) (type default))
  )
  (wire (pts (xy 121.92 105.41) (xy 115.57 105.41))
    (stroke (width 0) (type default))
  )
  (wire (pts (xy 62.23 66.04) (xy 62.23 68.58))
    (stroke (width 0) (type default))
  )
  (wire (pts (xy 144.78 74.93) (xy 138.43 74.93))
    (stroke (width 0) (type default))
  )
  (wire (pts (xy 68.58 73.66) (xy 68.58 74.93))
    (stroke (width 0) (type default))
  )
  (wire (pts (xy 115.57 95.25) (xy 121.92 95.25))
    (stroke (width 0) (type default))
  )
  (wire (pts (xy 109.22 105.41) (xy 115.57 105.41))
    (stroke (width 0) (type default))
  )
  (wire (pts (xy 96.52 105.41) (xy 102.87 105.41))
    (stroke (width 0) (type default))
  )
  (wire (pts (xy 107.95 138.43) (xy 101.6 138.43))
    (stroke (width 0) (type default))
  )
  (wire (pts (xy 200.66 87.63) (xy 200.66 85.09))
    (stroke (width 0) (type default))
  )
  (wire (pts (xy 63.5 138.43) (xy 63.5 140.97))
    (stroke (width 0) (type default))
  )
  (wire (pts (xy 125.73 66.04) (xy 119.38 66.04))
    (stroke (width 0) (type default))
  )
  (wire (pts (xy 144.78 66.04) (xy 138.43 66.04))
    (stroke (width 0) (type default))
  )
  (wire (pts (xy 36.83 73.66) (xy 36.83 74.93))
    (stroke (width 0) (type default))
  )
  (wire (pts (xy 109.22 102.87) (xy 109.22 105.41))
    (stroke (width 0) (type default))
  )
  (wire (pts (xy 157.48 66.04) (xy 151.13 66.04))
    (stroke (width 0) (type default))
  )
  (wire (pts (xy 157.48 73.66) (xy 157.48 74.93))
    (stroke (width 0) (type default))
  )
  (wire (pts (xy 93.98 66.04) (xy 93.98 68.58))
    (stroke (width 0) (type default))
  )
  (wire (pts (xy 332.74 102.87) (xy 326.39 102.87))
    (stroke (width 0) (type default))
  )
  (wire (pts (xy 49.53 66.04) (xy 49.53 68.58))
    (stroke (width 0) (type default))
  )
  (wire (pts (xy 259.08 146.05) (xy 309.88 146.05))
    (stroke (width 0) (type default))
  )
  (wire (pts (xy 125.73 165.1) (xy 119.38 165.1))
    (stroke (width 0) (type default))
  )
  (wire (pts (xy 309.88 153.67) (xy 309.88 154.94))
    (stroke (width 0) (type default))
  )
  (wire (pts (xy 49.53 73.66) (xy 49.53 74.93))
    (stroke (width 0) (type default))
  )
  (wire (pts (xy 90.17 95.25) (xy 90.17 97.79))
    (stroke (width 0) (type default))
  )
  (wire (pts (xy 332.74 92.71) (xy 332.74 93.98))
    (stroke (width 0) (type default))
  )
  (wire (pts (xy 201.93 87.63) (xy 200.66 87.63))
    (stroke (width 0) (type default))
  )
  (wire (pts (xy 69.85 130.81) (xy 69.85 128.27))
    (stroke (width 0) (type default))
  )
  (wire (pts (xy 83.82 102.87) (xy 83.82 105.41))
    (stroke (width 0) (type default))
  )
  (wire (pts (xy 106.68 74.93) (xy 100.33 74.93))
    (stroke (width 0) (type default))
  )
  (wire (pts (xy 326.39 93.98) (xy 318.77 93.98))
    (stroke (width 0) (type default))
  )
  (wire (pts (xy 240.03 83.82) (xy 246.38 83.82))
    (stroke (width 0) (type default))
  )
  (wire (pts (xy 95.25 138.43) (xy 95.25 135.89))
    (stroke (width 0) (type default))
  )
  (wire (pts (xy 167.64 81.28) (xy 201.93 81.28))
    (stroke (width 0) (type default))
  )
  (wire (pts (xy 115.57 102.87) (xy 115.57 105.41))
    (stroke (width 0) (type default))
  )
  (wire (pts (xy 144.78 73.66) (xy 144.78 74.93))
    (stroke (width 0) (type default))
  )
  (wire (pts (xy 125.73 165.1) (xy 125.73 167.64))
    (stroke (width 0) (type default))
  )
  (wire (pts (xy 88.9 138.43) (xy 88.9 135.89))
    (stroke (width 0) (type default))
  )
  (wire (pts (xy 113.03 66.04) (xy 113.03 68.58))
    (stroke (width 0) (type default))
  )
  (wire (pts (xy 125.73 66.04) (xy 125.73 68.58))
    (stroke (width 0) (type default))
  )
  (wire (pts (xy 107.95 128.27) (xy 101.6 128.27))
    (stroke (width 0) (type default))
  )
  (wire (pts (xy 100.33 66.04) (xy 93.98 66.04))
    (stroke (width 0) (type default))
  )
  (wire (pts (xy 102.87 95.25) (xy 102.87 97.79))
    (stroke (width 0) (type default))
  )
  (wire (pts (xy 62.23 66.04) (xy 55.88 66.04))
    (stroke (width 0) (type default))
  )
  (wire (pts (xy 327.66 118.11) (xy 327.66 119.38))
    (stroke (width 0) (type default))
  )
  (wire (pts (xy 326.39 101.6) (xy 326.39 102.87))
    (stroke (width 0) (type default))
  )
  (wire (pts (xy 316.23 81.28) (xy 316.23 78.74))
    (stroke (width 0) (type default))
  )
  (wire (pts (xy 327.66 121.92) (xy 327.66 119.38))
    (stroke (width 0) (type default))
  )
  (wire (pts (xy 69.85 138.43) (xy 63.5 138.43))
    (stroke (width 0) (type default))
  )
  (wire (pts (xy 74.93 73.66) (xy 74.93 74.93))
    (stroke (width 0) (type default))
  )
  (wire (pts (xy 121.92 95.25) (xy 142.24 95.25))
    (stroke (width 0) (type default))
  )
  (wire (pts (xy 119.38 66.04) (xy 113.03 66.04))
    (stroke (width 0) (type default))
  )
  (wire (pts (xy 115.57 95.25) (xy 115.57 97.79))
    (stroke (width 0) (type default))
  )
  (wire (pts (xy 332.74 72.39) (xy 325.12 72.39))
    (stroke (width 0) (type default))
  )
  (wire (pts (xy 125.73 173.99) (xy 119.38 173.99))
    (stroke (width 0) (type default))
  )
  (wire (pts (xy 109.22 95.25) (xy 109.22 97.79))
    (stroke (width 0) (type default))
  )
  (wire (pts (xy 76.2 128.27) (xy 69.85 128.27))
    (stroke (width 0) (type default))
  )
  (wire (pts (xy 201.93 90.17) (xy 200.66 90.17))
    (stroke (width 0) (type default))
  )
  (wire (pts (xy 68.58 172.72) (xy 68.58 173.99))
    (stroke (width 0) (type default))
  )
  (wire (pts (xy 107.95 138.43) (xy 107.95 135.89))
    (stroke (width 0) (type default))
  )
  (wire (pts (xy 246.38 91.44) (xy 259.08 91.44))
    (stroke (width 0) (type default))
  )
  (wire (pts (xy 77.47 105.41) (xy 83.82 105.41))
    (stroke (width 0) (type default))
  )
  (wire (pts (xy 259.08 91.44) (xy 259.08 146.05))
    (stroke (width 0) (type default))
  )
  (wire (pts (xy 325.12 81.28) (xy 325.12 78.74))
    (stroke (width 0) (type default))
  )
  (wire (pts (xy 320.04 121.92) (xy 320.04 119.38))
    (stroke (width 0) (type default))
  )
  (wire (pts (xy 125.73 73.66) (xy 125.73 74.93))
    (stroke (width 0) (type default))
  )
  (wire (pts (xy 377.19 72.39) (xy 358.14 72.39))
    (stroke (width 0) (type default))
  )
  (wire (pts (xy 325.12 73.66) (xy 325.12 72.39))
    (stroke (width 0) (type default))
  )
  (wire (pts (xy 144.78 66.04) (xy 144.78 68.58))
    (stroke (width 0) (type default))
  )
  (wire (pts (xy 325.12 72.39) (xy 316.23 72.39))
    (stroke (width 0) (type default))
  )
  (wire (pts (xy 290.83 81.28) (xy 290.83 93.98))
    (stroke (width 0) (type default))
  )
  (wire (pts (xy 290.83 93.98) (xy 318.77 93.98))
    (stroke (width 0) (type default))
  )
  (wire (pts (xy 323.85 146.05) (xy 317.5 146.05))
    (stroke (width 0) (type default))
  )
  (wire (pts (xy 71.12 105.41) (xy 77.47 105.41))
    (stroke (width 0) (type default))
  )
  (wire (pts (xy 119.38 73.66) (xy 119.38 74.93))
    (stroke (width 0) (type default))
  )
  (wire (pts (xy 327.66 119.38) (xy 320.04 119.38))
    (stroke (width 0) (type default))
  )
  (wire (pts (xy 63.5 128.27) (xy 52.07 128.27))
    (stroke (width 0) (type default))
  )
  (wire (pts (xy 132.08 73.66) (xy 132.08 74.93))
    (stroke (width 0) (type default))
  )
  (wire (pts (xy 63.5 138.43) (xy 63.5 135.89))
    (stroke (width 0) (type default))
  )
  (wire (pts (xy 332.74 71.12) (xy 332.74 72.39))
    (stroke (width 0) (type default))
  )
  (wire (pts (xy 163.83 66.04) (xy 163.83 76.2))
    (stroke (width 0) (type default))
  )
  (wire (pts (xy 121.92 95.25) (xy 121.92 97.79))
    (stroke (width 0) (type default))
  )
  (wire (pts (xy 95.25 138.43) (xy 88.9 138.43))
    (stroke (width 0) (type default))
  )
  (wire (pts (xy 101.6 128.27) (xy 95.25 128.27))
    (stroke (width 0) (type default))
  )
  (wire (pts (xy 332.74 102.87) (xy 332.74 105.41))
    (stroke (width 0) (type default))
  )
  (wire (pts (xy 181.61 85.09) (xy 200.66 85.09))
    (stroke (width 0) (type default))
  )
  (wire (pts (xy 113.03 165.1) (xy 106.68 165.1))
    (stroke (width 0) (type default))
  )
  (wire (pts (xy 30.48 74.93) (xy 30.48 77.47))
    (stroke (width 0) (type default))
  )
  (wire (pts (xy 90.17 105.41) (xy 96.52 105.41))
    (stroke (width 0) (type default))
  )
  (wire (pts (xy 82.55 130.81) (xy 82.55 128.27))
    (stroke (width 0) (type default))
  )
  (wire (pts (xy 88.9 128.27) (xy 82.55 128.27))
    (stroke (width 0) (type default))
  )
  (wire (pts (xy 157.48 66.04) (xy 163.83 66.04))
    (stroke (width 0) (type default))
  )
  (wire (pts (xy 62.23 73.66) (xy 62.23 74.93))
    (stroke (width 0) (type default))
  )
  (wire (pts (xy 316.23 73.66) (xy 316.23 72.39))
    (stroke (width 0) (type default))
  )
  (wire (pts (xy 106.68 66.04) (xy 100.33 66.04))
    (stroke (width 0) (type default))
  )
  (wire (pts (xy 323.85 153.67) (xy 323.85 154.94))
    (stroke (width 0) (type default))
  )
  (wire (pts (xy 326.39 93.98) (xy 326.39 96.52))
    (stroke (width 0) (type default))
  )
  (wire (pts (xy 332.74 81.28) (xy 325.12 81.28))
    (stroke (width 0) (type default))
  )
  (wire (pts (xy 323.85 154.94) (xy 317.5 154.94))
    (stroke (width 0) (type default))
  )
  (wire (pts (xy 107.95 130.81) (xy 107.95 128.27))
    (stroke (width 0) (type default))
  )
  (wire (pts (xy 125.73 74.93) (xy 119.38 74.93))
    (stroke (width 0) (type default))
  )
  (wire (pts (xy 83.82 95.25) (xy 83.82 97.79))
    (stroke (width 0) (type default))
  )
  (wire (pts (xy 74.93 165.1) (xy 74.93 167.64))
    (stroke (width 0) (type default))
  )
  (wire (pts (xy 62.23 165.1) (xy 62.23 167.64))
    (stroke (width 0) (type default))
  )
  (wire (pts (xy 74.93 66.04) (xy 68.58 66.04))
    (stroke (width 0) (type default))
  )
  (wire (pts (xy 246.38 76.2) (xy 292.1 76.2))
    (stroke (width 0) (type default))
  )
  (wire (pts (xy 240.03 86.36) (xy 246.38 86.36))
    (stroke (width 0) (type default))
  )
  (wire (pts (xy 246.38 81.28) (xy 290.83 81.28))
    (stroke (width 0) (type default))
  )
  (wire (pts (xy 30.48 66.04) (xy 27.94 66.04))
    (stroke (width 0) (type default))
  )
  (wire (pts (xy 96.52 95.25) (xy 96.52 97.79))
    (stroke (width 0) (type default))
  )
  (wire (pts (xy 43.18 74.93) (xy 36.83 74.93))
    (stroke (width 0) (type default))
  )
  (wire (pts (xy 87.63 66.04) (xy 81.28 66.04))
    (stroke (width 0) (type default))
  )
  (wire (pts (xy 246.38 78.74) (xy 246.38 76.2))
    (stroke (width 0) (type default))
  )
  (wire (pts (xy 95.25 130.81) (xy 95.25 128.27))
    (stroke (width 0) (type default))
  )
  (wire (pts (xy 240.03 76.2) (xy 246.38 76.2))
    (stroke (width 0) (type default))
  )
  (wire (pts (xy 81.28 165.1) (xy 81.28 167.64))
    (stroke (width 0) (type default))
  )
  (wire (pts (xy 77.47 102.87) (xy 77.47 105.41))
    (stroke (width 0) (type default))
  )
  (wire (pts (xy 317.5 146.05) (xy 317.5 148.59))
    (stroke (width 0) (type default))
  )
  (wire (pts (xy 74.93 172.72) (xy 74.93 173.99))
    (stroke (width 0) (type default))
  )
  (wire (pts (xy 151.13 66.04) (xy 144.78 66.04))
    (stroke (width 0) (type default))
  )
  (wire (pts (xy 96.52 95.25) (xy 102.87 95.25))
    (stroke (width 0) (type default))
  )
  (wire (pts (xy 132.08 173.99) (xy 125.73 173.99))
    (stroke (width 0) (type default))
  )
  (wire (pts (xy 167.64 128.27) (xy 167.64 81.28))
    (stroke (width 0) (type default))
  )
  (wire (pts (xy 132.08 66.04) (xy 125.73 66.04))
    (stroke (width 0) (type default))
  )
  (wire (pts (xy 68.58 165.1) (xy 68.58 167.64))
    (stroke (width 0) (type default))
  )
  (wire (pts (xy 332.74 146.05) (xy 323.85 146.05))
    (stroke (width 0) (type default))
  )
  (wire (pts (xy 93.98 172.72) (xy 93.98 173.99))
    (stroke (width 0) (type default))
  )
  (wire (pts (xy 100.33 172.72) (xy 100.33 173.99))
    (stroke (width 0) (type default))
  )
  (wire (pts (xy 113.03 66.04) (xy 106.68 66.04))
    (stroke (width 0) (type default))
  )
  (wire (pts (xy 327.66 129.54) (xy 327.66 127))
    (stroke (width 0) (type default))
  )
  (wire (pts (xy 353.06 72.39) (xy 332.74 72.39))
    (stroke (width 0) (type default))
  )
  (wire (pts (xy 317.5 154.94) (xy 309.88 154.94))
    (stroke (width 0) (type default))
  )
  (wire (pts (xy 82.55 138.43) (xy 76.2 138.43))
    (stroke (width 0) (type default))
  )
  (wire (pts (xy 106.68 66.04) (xy 106.68 68.58))
    (stroke (width 0) (type default))
  )
  (wire (pts (xy 119.38 165.1) (xy 119.38 167.64))
    (stroke (width 0) (type default))
  )
  (wire (pts (xy 125.73 172.72) (xy 125.73 173.99))
    (stroke (width 0) (type default))
  )
  (wire (pts (xy 30.48 73.66) (xy 30.48 74.93))
    (stroke (width 0) (type default))
  )
  (wire (pts (xy 273.05 119.38) (xy 312.42 119.38))
    (stroke (width 0) (type default))
  )
  (wire (pts (xy 74.93 74.93) (xy 68.58 74.93))
    (stroke (width 0) (type default))
  )
  (wire (pts (xy 292.1 72.39) (xy 316.23 72.39))
    (stroke (width 0) (type default))
  )
  (wire (pts (xy 102.87 102.87) (xy 102.87 105.41))
    (stroke (width 0) (type default))
  )
  (wire (pts (xy 132.08 165.1) (xy 181.61 165.1))
    (stroke (width 0) (type default))
  )
  (wire (pts (xy 132.08 66.04) (xy 132.08 68.58))
    (stroke (width 0) (type default))
  )
  (wire (pts (xy 74.93 173.99) (xy 68.58 173.99))
    (stroke (width 0) (type default))
  )
  (wire (pts (xy 43.18 66.04) (xy 43.18 68.58))
    (stroke (width 0) (type default))
  )
  (wire (pts (xy 87.63 165.1) (xy 87.63 167.64))
    (stroke (width 0) (type default))
  )
  (wire (pts (xy 121.92 102.87) (xy 121.92 105.41))
    (stroke (width 0) (type default))
  )
  (wire (pts (xy 240.03 116.84) (xy 242.57 116.84))
    (stroke (width 0) (type default))
  )
  (wire (pts (xy 36.83 165.1) (xy 29.21 165.1))
    (stroke (width 0) (type default))
  )
  (wire (pts (xy 87.63 165.1) (xy 81.28 165.1))
    (stroke (width 0) (type default))
  )
  (wire (pts (xy 43.18 73.66) (xy 43.18 74.93))
    (stroke (width 0) (type default))
  )
  (wire (pts (xy 102.87 95.25) (xy 109.22 95.25))
    (stroke (width 0) (type default))
  )
  (wire (pts (xy 113.03 172.72) (xy 113.03 173.99))
    (stroke (width 0) (type default))
  )
  (wire (pts (xy 81.28 66.04) (xy 81.28 68.58))
    (stroke (width 0) (type default))
  )
  (wire (pts (xy 82.55 138.43) (xy 82.55 135.89))
    (stroke (width 0) (type default))
  )
  (wire (pts (xy 55.88 74.93) (xy 49.53 74.93))
    (stroke (width 0) (type default))
  )
  (wire (pts (xy 240.03 88.9) (xy 246.38 88.9))
    (stroke (width 0) (type default))
  )
  (wire (pts (xy 43.18 66.04) (xy 36.83 66.04))
    (stroke (width 0) (type default))
  )
  (wire (pts (xy 114.3 130.81) (xy 114.3 128.27))
    (stroke (width 0) (type default))
  )
  (wire (pts (xy 240.03 78.74) (xy 246.38 78.74))
    (stroke (width 0) (type default))
  )
  (wire (pts (xy 132.08 165.1) (xy 125.73 165.1))
    (stroke (width 0) (type default))
  )
  (wire (pts (xy 100.33 173.99) (xy 93.98 173.99))
    (stroke (width 0) (type default))
  )
  (wire (pts (xy 93.98 165.1) (xy 87.63 165.1))
    (stroke (width 0) (type default))
  )
  (wire (pts (xy 77.47 95.25) (xy 83.82 95.25))
    (stroke (width 0) (type default))
  )
  (wire (pts (xy 69.85 138.43) (xy 69.85 135.89))
    (stroke (width 0) (type default))
  )

  (text "Power supply" (at 207.01 63.5 0)
    (effects (font (size 2.9972 2.9972)) (justify left bottom))
  )

  (label "VCCA1" (at 332.74 146.05 180) (fields_autoplaced)
    (effects (font (size 1.27 1.27)) (justify right bottom))
  )
  (label "VCCA0" (at 46.99 95.25 0) (fields_autoplaced)
    (effects (font (size 1.27 1.27)) (justify left bottom))
  )
  (label "VCCHTX1" (at 345.44 119.38 180) (fields_autoplaced)
    (effects (font (size 1.27 1.27)) (justify right bottom))
  )
  (label "VCCHTX0" (at 350.52 72.39 180) (fields_autoplaced)
    (effects (font (size 1.27 1.27)) (justify right bottom))
  )
  (label "VCCAUX" (at 54.61 165.1 180) (fields_autoplaced)
    (effects (font (size 1.27 1.27)) (justify right bottom))
  )
  (label "VCCA0" (at 344.17 93.98 180) (fields_autoplaced)
    (effects (font (size 1.27 1.27)) (justify right bottom))
  )
  (label "VCCA1" (at 59.69 128.27 180) (fields_autoplaced)
    (effects (font (size 1.27 1.27)) (justify right bottom))
  )

  (global_label "VCC1V2" (shape input) (at 377.19 72.39 0) (fields_autoplaced)
    (effects (font (size 1.27 1.27)) (justify left))
    (property "Intersheetrefs" "${INTERSHEET_REFS}" (at 466.09 -60.96 0)
      (effects (font (size 1.27 1.27)) hide)
    )
  )
  (global_label "VCC1V2" (shape input) (at 27.94 66.04 180) (fields_autoplaced)
    (effects (font (size 1.27 1.27)) (justify right))
    (property "Intersheetrefs" "${INTERSHEET_REFS}" (at 410.21 -30.48 0)
      (effects (font (size 1.27 1.27)) hide)
    )
  )
  (global_label "VCC1V2" (shape input) (at 372.11 119.38 0) (fields_autoplaced)
    (effects (font (size 1.27 1.27)) (justify left))
    (property "Intersheetrefs" "${INTERSHEET_REFS}" (at 461.645 -49.53 0)
      (effects (font (size 1.27 1.27)) hide)
    )
  )
  (global_label "VCC1V2" (shape input) (at 29.21 128.27 180) (fields_autoplaced)
    (effects (font (size 1.27 1.27)) (justify right))
    (property "Intersheetrefs" "${INTERSHEET_REFS}" (at 377.19 5.08 0)
      (effects (font (size 1.27 1.27)) hide)
    )
  )
  (global_label "VCC2V5" (shape input) (at 29.21 165.1 180) (fields_autoplaced)
    (effects (font (size 1.27 1.27)) (justify right))
    (property "Intersheetrefs" "${INTERSHEET_REFS}" (at 377.19 1.27 0)
      (effects (font (size 1.27 1.27)) hide)
    )
  )
  (global_label "VCC1V2" (shape input) (at 27.94 95.25 180) (fields_autoplaced)
    (effects (font (size 1.27 1.27)) (justify right))
    (property "Intersheetrefs" "${INTERSHEET_REFS}" (at -41.91 -21.59 0)
      (effects (font (size 1.27 1.27)) hide)
    )
  )

  (symbol (lib_id "antmicroCapacitors0402:C_470n_0402") (at 68.58 172.72 270) (mirror x) (unit 1)
    (in_bom yes) (on_board yes) (dnp no)
    (property "Reference" "C184" (at 71.12 172.085 0)
      (effects (font (size 1.524 1.524)) (justify left))
    )
    (property "Value" "C_470n_0402" (at 64.77 172.72 0)
      (effects (font (size 1.524 1.524)) hide)
    )
    (property "Footprint" "antmicro-footprints:C_0402_1005Metric" (at 73.66 167.64 0)
      (effects (font (size 1.524 1.524)) (justify left) hide)
    )
    (property "Datasheet" "https://product.tdk.com/en/search/capacitor/ceramic/mlcc/info?part_no=C1005X5R1E474M050BB" (at 68.58 172.72 0)
      (effects (font (size 1.27 1.27)) hide)
    )
    (property "Manufacturer" "TDK" (at 78.74 167.64 0)
      (effects (font (size 1.524 1.524)) (justify left) hide)
    )
    (property "MPN" "C1005X5R1E474M050BB" (at 76.2 167.64 0)
      (effects (font (size 1.524 1.524)) (justify left) hide)
    )
    (property "Val" "470n" (at 66.04 172.085 0)
      (effects (font (size 1.27 1.27)) (justify left))
    )
    (property "License" "Apache-2.0" (at 45.72 152.4 0)
      (effects (font (size 1.27 1.27) (thickness 0.15)) (justify left bottom) hide)
    )
    (property "Author" "Antmicro" (at 43.18 152.4 0)
      (effects (font (size 1.27 1.27) (thickness 0.15)) (justify left bottom) hide)
    )
    (property "Voltage" "" (at 40.64 152.4 0)
      (effects (font (size 1.27 1.27)) (justify left bottom) hide)
    )
    (property "Dielectric" "" (at 38.1 152.4 0)
      (effects (font (size 1.27 1.27)) (justify left bottom) hide)
    )
    (property "Public" "False" (at 35.56 152.4 0)
      (effects (font (size 1.27 1.27)) (justify left bottom) hide)
    )
    (pin "1")
    (pin "2")
    (instances
      (project "ecp5-dc-scm"
        (path ""
          (reference "C184") (unit 1)
        )
      )
    )
  )

  (symbol (lib_id "antmicroCapacitors0402:C_470n_0402") (at 62.23 172.72 270) (mirror x) (unit 1)
    (in_bom yes) (on_board yes) (dnp no)
    (property "Reference" "C186" (at 64.77 172.085 0)
      (effects (font (size 1.524 1.524)) (justify left))
    )
    (property "Value" "C_470n_0402" (at 58.42 172.72 0)
      (effects (font (size 1.524 1.524)) hide)
    )
    (property "Footprint" "antmicro-footprints:C_0402_1005Metric" (at 67.31 167.64 0)
      (effects (font (size 1.524 1.524)) (justify left) hide)
    )
    (property "Datasheet" "https://product.tdk.com/en/search/capacitor/ceramic/mlcc/info?part_no=C1005X5R1E474M050BB" (at 62.23 172.72 0)
      (effects (font (size 1.27 1.27)) hide)
    )
    (property "Manufacturer" "TDK" (at 72.39 167.64 0)
      (effects (font (size 1.524 1.524)) (justify left) hide)
    )
    (property "MPN" "C1005X5R1E474M050BB" (at 69.85 167.64 0)
      (effects (font (size 1.524 1.524)) (justify left) hide)
    )
    (property "Val" "470n" (at 59.69 172.085 0)
      (effects (font (size 1.27 1.27)) (justify left))
    )
    (property "License" "Apache-2.0" (at 39.37 152.4 0)
      (effects (font (size 1.27 1.27) (thickness 0.15)) (justify left bottom) hide)
    )
    (property "Author" "Antmicro" (at 36.83 152.4 0)
      (effects (font (size 1.27 1.27) (thickness 0.15)) (justify left bottom) hide)
    )
    (property "Voltage" "" (at 34.29 152.4 0)
      (effects (font (size 1.27 1.27)) (justify left bottom) hide)
    )
    (property "Dielectric" "" (at 31.75 152.4 0)
      (effects (font (size 1.27 1.27)) (justify left bottom) hide)
    )
    (property "Public" "False" (at 29.21 152.4 0)
      (effects (font (size 1.27 1.27)) (justify left bottom) hide)
    )
    (pin "1")
    (pin "2")
    (instances
      (project "ecp5-dc-scm"
        (path ""
          (reference "C186") (unit 1)
        )
      )
    )
  )

  (symbol (lib_id "antmicroCapacitors0603:C_47u_0603") (at 30.48 68.58 90) (mirror x) (unit 1)
    (in_bom yes) (on_board yes) (dnp no)
    (property "Reference" "C154" (at 29.845 69.85 90)
      (effects (font (size 1.524 1.524)) (justify left))
    )
    (property "Value" "C_47u_0603" (at 34.29 68.58 0)
      (effects (font (size 1.524 1.524)) hide)
    )
    (property "Footprint" "antmicro-footprints:C_0603_1608Metric" (at 25.4 73.66 0)
      (effects (font (size 1.524 1.524)) (justify left) hide)
    )
    (property "Datasheet" "https://www.murata.com/products/productdetail?partno=GRM188R60J476ME15%23" (at 30.48 68.58 0)
      (effects (font (size 1.27 1.27)) hide)
    )
    (property "Manufacturer" "Murata" (at 20.32 73.66 0)
      (effects (font (size 1.524 1.524)) (justify left) hide)
    )
    (property "MPN" "GRM188R60J476ME15D" (at 22.86 73.66 0)
      (effects (font (size 1.524 1.524)) (justify left) hide)
    )
    (property "Val" "47u" (at 29.21 73.025 90)
      (effects (font (size 1.27 1.27)) (justify left))
    )
    (property "License" "Apache-2.0" (at 53.34 88.9 0)
      (effects (font (size 1.27 1.27) (thickness 0.15)) (justify left bottom) hide)
    )
    (property "Author" "Antmicro" (at 55.88 88.9 0)
      (effects (font (size 1.27 1.27) (thickness 0.15)) (justify left bottom) hide)
    )
    (property "Voltage" "" (at 58.42 88.9 0)
      (effects (font (size 1.27 1.27)) (justify left bottom) hide)
    )
    (property "Dielectric" "" (at 60.96 88.9 0)
      (effects (font (size 1.27 1.27)) (justify left bottom) hide)
    )
    (property "Public" "False" (at 63.5 88.9 0)
      (effects (font (size 1.27 1.27)) (justify left bottom) hide)
    )
    (pin "1")
    (pin "2")
    (instances
      (project "ecp5-dc-scm"
        (path ""
          (reference "C154") (unit 1)
        )
      )
    )
  )

  (symbol (lib_id "antmicroCapacitors0402:C_4u7_0402") (at 36.83 68.58 90) (mirror x) (unit 1)
    (in_bom yes) (on_board yes) (dnp no)
    (property "Reference" "C156" (at 36.83 69.85 90)
      (effects (font (size 1.524 1.524)) (justify left))
    )
    (property "Value" "C_4u7_0402" (at 40.64 68.58 0)
      (effects (font (size 1.524 1.524)) hide)
    )
    (property "Footprint" "antmicro-footprints:C_0402_1005Metric" (at 31.75 73.66 0)
      (effects (font (size 1.524 1.524)) (justify left) hide)
    )
    (property "Datasheet" "https://www.murata.com/products/productdetail?partno=GRM155R61A475MEAA%23" (at 36.83 68.58 0)
      (effects (font (size 1.27 1.27)) hide)
    )
    (property "Manufacturer" "Murata" (at 26.67 73.66 0)
      (effects (font (size 1.524 1.524)) (justify left) hide)
    )
    (property "MPN" "GRM155R61A475MEAAD" (at 29.21 73.66 0)
      (effects (font (size 1.524 1.524)) (justify left) hide)
    )
    (property "Val" "4u7" (at 35.56 73.025 90)
      (effects (font (size 1.27 1.27)) (justify left))
    )
    (property "License" "Apache-2.0" (at 59.69 88.9 0)
      (effects (font (size 1.27 1.27) (thickness 0.15)) (justify left bottom) hide)
    )
    (property "Author" "Antmicro" (at 62.23 88.9 0)
      (effects (font (size 1.27 1.27) (thickness 0.15)) (justify left bottom) hide)
    )
    (property "Voltage" "" (at 64.77 88.9 0)
      (effects (font (size 1.27 1.27)) (justify left bottom) hide)
    )
    (property "Dielectric" "" (at 67.31 88.9 0)
      (effects (font (size 1.27 1.27)) (justify left bottom) hide)
    )
    (property "Public" "False" (at 69.85 88.9 0)
      (effects (font (size 1.27 1.27)) (justify left bottom) hide)
    )
    (pin "1")
    (pin "2")
    (instances
      (project "ecp5-dc-scm"
        (path ""
          (reference "C156") (unit 1)
        )
      )
    )
  )

  (symbol (lib_id "antmicroCapacitors0402:C_4u7_0402") (at 43.18 68.58 90) (mirror x) (unit 1)
    (in_bom yes) (on_board yes) (dnp no)
    (property "Reference" "C159" (at 43.18 69.85 90)
      (effects (font (size 1.524 1.524)) (justify left))
    )
    (property "Value" "C_4u7_0402" (at 46.99 68.58 0)
      (effects (font (size 1.524 1.524)) hide)
    )
    (property "Footprint" "antmicro-footprints:C_0402_1005Metric" (at 38.1 73.66 0)
      (effects (font (size 1.524 1.524)) (justify left) hide)
    )
    (property "Datasheet" "https://www.murata.com/products/productdetail?partno=GRM155R61A475MEAA%23" (at 43.18 68.58 0)
      (effects (font (size 1.27 1.27)) hide)
    )
    (property "Manufacturer" "Murata" (at 33.02 73.66 0)
      (effects (font (size 1.524 1.524)) (justify left) hide)
    )
    (property "MPN" "GRM155R61A475MEAAD" (at 35.56 73.66 0)
      (effects (font (size 1.524 1.524)) (justify left) hide)
    )
    (property "Val" "4u7" (at 41.91 73.025 90)
      (effects (font (size 1.27 1.27)) (justify left))
    )
    (property "License" "Apache-2.0" (at 66.04 88.9 0)
      (effects (font (size 1.27 1.27) (thickness 0.15)) (justify left bottom) hide)
    )
    (property "Author" "Antmicro" (at 68.58 88.9 0)
      (effects (font (size 1.27 1.27) (thickness 0.15)) (justify left bottom) hide)
    )
    (property "Voltage" "" (at 71.12 88.9 0)
      (effects (font (size 1.27 1.27)) (justify left bottom) hide)
    )
    (property "Dielectric" "" (at 73.66 88.9 0)
      (effects (font (size 1.27 1.27)) (justify left bottom) hide)
    )
    (property "Public" "False" (at 76.2 88.9 0)
      (effects (font (size 1.27 1.27)) (justify left bottom) hide)
    )
    (pin "1")
    (pin "2")
    (instances
      (project "ecp5-dc-scm"
        (path ""
          (reference "C159") (unit 1)
        )
      )
    )
  )

  (symbol (lib_id "antmicroCapacitors0402:C_470n_0402") (at 49.53 68.58 90) (mirror x) (unit 1)
    (in_bom yes) (on_board yes) (dnp no)
    (property "Reference" "C162" (at 49.53 69.85 90)
      (effects (font (size 1.524 1.524)) (justify left))
    )
    (property "Value" "C_470n_0402" (at 53.34 68.58 0)
      (effects (font (size 1.524 1.524)) hide)
    )
    (property "Footprint" "antmicro-footprints:C_0402_1005Metric" (at 44.45 73.66 0)
      (effects (font (size 1.524 1.524)) (justify left) hide)
    )
    (property "Datasheet" "https://product.tdk.com/en/search/capacitor/ceramic/mlcc/info?part_no=C1005X5R1E474M050BB" (at 49.53 68.58 0)
      (effects (font (size 1.27 1.27)) hide)
    )
    (property "Manufacturer" "TDK" (at 39.37 73.66 0)
      (effects (font (size 1.524 1.524)) (justify left) hide)
    )
    (property "MPN" "C1005X5R1E474M050BB" (at 41.91 73.66 0)
      (effects (font (size 1.524 1.524)) (justify left) hide)
    )
    (property "Val" "470n" (at 48.26 73.025 90)
      (effects (font (size 1.27 1.27)) (justify left))
    )
    (property "License" "Apache-2.0" (at 72.39 88.9 0)
      (effects (font (size 1.27 1.27) (thickness 0.15)) (justify left bottom) hide)
    )
    (property "Author" "Antmicro" (at 74.93 88.9 0)
      (effects (font (size 1.27 1.27) (thickness 0.15)) (justify left bottom) hide)
    )
    (property "Voltage" "" (at 77.47 88.9 0)
      (effects (font (size 1.27 1.27)) (justify left bottom) hide)
    )
    (property "Dielectric" "" (at 80.01 88.9 0)
      (effects (font (size 1.27 1.27)) (justify left bottom) hide)
    )
    (property "Public" "False" (at 82.55 88.9 0)
      (effects (font (size 1.27 1.27)) (justify left bottom) hide)
    )
    (pin "1")
    (pin "2")
    (instances
      (project "ecp5-dc-scm"
        (path ""
          (reference "C162") (unit 1)
        )
      )
    )
  )

  (symbol (lib_id "antmicroCapacitors0402:C_470n_0402") (at 55.88 68.58 90) (mirror x) (unit 1)
    (in_bom yes) (on_board yes) (dnp no)
    (property "Reference" "C165" (at 55.88 69.85 90)
      (effects (font (size 1.524 1.524)) (justify left))
    )
    (property "Value" "C_470n_0402" (at 59.69 68.58 0)
      (effects (font (size 1.524 1.524)) hide)
    )
    (property "Footprint" "antmicro-footprints:C_0402_1005Metric" (at 50.8 73.66 0)
      (effects (font (size 1.524 1.524)) (justify left) hide)
    )
    (property "Datasheet" "https://product.tdk.com/en/search/capacitor/ceramic/mlcc/info?part_no=C1005X5R1E474M050BB" (at 55.88 68.58 0)
      (effects (font (size 1.27 1.27)) hide)
    )
    (property "Manufacturer" "TDK" (at 45.72 73.66 0)
      (effects (font (size 1.524 1.524)) (justify left) hide)
    )
    (property "MPN" "C1005X5R1E474M050BB" (at 48.26 73.66 0)
      (effects (font (size 1.524 1.524)) (justify left) hide)
    )
    (property "Val" "470n" (at 54.61 73.025 90)
      (effects (font (size 1.27 1.27)) (justify left))
    )
    (property "License" "Apache-2.0" (at 78.74 88.9 0)
      (effects (font (size 1.27 1.27) (thickness 0.15)) (justify left bottom) hide)
    )
    (property "Author" "Antmicro" (at 81.28 88.9 0)
      (effects (font (size 1.27 1.27) (thickness 0.15)) (justify left bottom) hide)
    )
    (property "Voltage" "" (at 83.82 88.9 0)
      (effects (font (size 1.27 1.27)) (justify left bottom) hide)
    )
    (property "Dielectric" "" (at 86.36 88.9 0)
      (effects (font (size 1.27 1.27)) (justify left bottom) hide)
    )
    (property "Public" "False" (at 88.9 88.9 0)
      (effects (font (size 1.27 1.27)) (justify left bottom) hide)
    )
    (pin "1")
    (pin "2")
    (instances
      (project "ecp5-dc-scm"
        (path ""
          (reference "C165") (unit 1)
        )
      )
    )
  )

  (symbol (lib_id "antmicroCapacitors0402:C_470n_0402") (at 62.23 68.58 90) (mirror x) (unit 1)
    (in_bom yes) (on_board yes) (dnp no)
    (property "Reference" "C168" (at 61.595 69.85 90)
      (effects (font (size 1.524 1.524)) (justify left))
    )
    (property "Value" "C_470n_0402" (at 66.04 68.58 0)
      (effects (font (size 1.524 1.524)) hide)
    )
    (property "Footprint" "antmicro-footprints:C_0402_1005Metric" (at 57.15 73.66 0)
      (effects (font (size 1.524 1.524)) (justify left) hide)
    )
    (property "Datasheet" "https://product.tdk.com/en/search/capacitor/ceramic/mlcc/info?part_no=C1005X5R1E474M050BB" (at 62.23 68.58 0)
      (effects (font (size 1.27 1.27)) hide)
    )
    (property "Manufacturer" "TDK" (at 52.07 73.66 0)
      (effects (font (size 1.524 1.524)) (justify left) hide)
    )
    (property "MPN" "C1005X5R1E474M050BB" (at 54.61 73.66 0)
      (effects (font (size 1.524 1.524)) (justify left) hide)
    )
    (property "Val" "470n" (at 61.595 73.025 90)
      (effects (font (size 1.27 1.27)) (justify left))
    )
    (property "License" "Apache-2.0" (at 85.09 88.9 0)
      (effects (font (size 1.27 1.27) (thickness 0.15)) (justify left bottom) hide)
    )
    (property "Author" "Antmicro" (at 87.63 88.9 0)
      (effects (font (size 1.27 1.27) (thickness 0.15)) (justify left bottom) hide)
    )
    (property "Voltage" "" (at 90.17 88.9 0)
      (effects (font (size 1.27 1.27)) (justify left bottom) hide)
    )
    (property "Dielectric" "" (at 92.71 88.9 0)
      (effects (font (size 1.27 1.27)) (justify left bottom) hide)
    )
    (property "Public" "False" (at 95.25 88.9 0)
      (effects (font (size 1.27 1.27)) (justify left bottom) hide)
    )
    (pin "1")
    (pin "2")
    (instances
      (project "ecp5-dc-scm"
        (path ""
          (reference "C168") (unit 1)
        )
      )
    )
  )

  (symbol (lib_id "antmicroCapacitors0402:C_470n_0402") (at 68.58 68.58 90) (mirror x) (unit 1)
    (in_bom yes) (on_board yes) (dnp no)
    (property "Reference" "C171" (at 67.945 69.85 90)
      (effects (font (size 1.524 1.524)) (justify left))
    )
    (property "Value" "C_470n_0402" (at 72.39 68.58 0)
      (effects (font (size 1.524 1.524)) hide)
    )
    (property "Footprint" "antmicro-footprints:C_0402_1005Metric" (at 63.5 73.66 0)
      (effects (font (size 1.524 1.524)) (justify left) hide)
    )
    (property "Datasheet" "https://product.tdk.com/en/search/capacitor/ceramic/mlcc/info?part_no=C1005X5R1E474M050BB" (at 68.58 68.58 0)
      (effects (font (size 1.27 1.27)) hide)
    )
    (property "Manufacturer" "TDK" (at 58.42 73.66 0)
      (effects (font (size 1.524 1.524)) (justify left) hide)
    )
    (property "MPN" "C1005X5R1E474M050BB" (at 60.96 73.66 0)
      (effects (font (size 1.524 1.524)) (justify left) hide)
    )
    (property "Val" "470n" (at 67.31 73.025 90)
      (effects (font (size 1.27 1.27)) (justify left))
    )
    (property "License" "Apache-2.0" (at 91.44 88.9 0)
      (effects (font (size 1.27 1.27) (thickness 0.15)) (justify left bottom) hide)
    )
    (property "Author" "Antmicro" (at 93.98 88.9 0)
      (effects (font (size 1.27 1.27) (thickness 0.15)) (justify left bottom) hide)
    )
    (property "Voltage" "" (at 96.52 88.9 0)
      (effects (font (size 1.27 1.27)) (justify left bottom) hide)
    )
    (property "Dielectric" "" (at 99.06 88.9 0)
      (effects (font (size 1.27 1.27)) (justify left bottom) hide)
    )
    (property "Public" "False" (at 101.6 88.9 0)
      (effects (font (size 1.27 1.27)) (justify left bottom) hide)
    )
    (pin "1")
    (pin "2")
    (instances
      (project "ecp5-dc-scm"
        (path ""
          (reference "C171") (unit 1)
        )
      )
    )
  )

  (symbol (lib_id "antmicroCapacitors0402:C_470n_0402") (at 74.93 68.58 90) (mirror x) (unit 1)
    (in_bom yes) (on_board yes) (dnp no)
    (property "Reference" "C174" (at 74.295 69.85 90)
      (effects (font (size 1.524 1.524)) (justify left))
    )
    (property "Value" "C_470n_0402" (at 78.74 68.58 0)
      (effects (font (size 1.524 1.524)) hide)
    )
    (property "Footprint" "antmicro-footprints:C_0402_1005Metric" (at 69.85 73.66 0)
      (effects (font (size 1.524 1.524)) (justify left) hide)
    )
    (property "Datasheet" "https://product.tdk.com/en/search/capacitor/ceramic/mlcc/info?part_no=C1005X5R1E474M050BB" (at 74.93 68.58 0)
      (effects (font (size 1.27 1.27)) hide)
    )
    (property "Manufacturer" "TDK" (at 64.77 73.66 0)
      (effects (font (size 1.524 1.524)) (justify left) hide)
    )
    (property "MPN" "C1005X5R1E474M050BB" (at 67.31 73.66 0)
      (effects (font (size 1.524 1.524)) (justify left) hide)
    )
    (property "Val" "470n" (at 73.66 73.025 90)
      (effects (font (size 1.27 1.27)) (justify left))
    )
    (property "License" "Apache-2.0" (at 97.79 88.9 0)
      (effects (font (size 1.27 1.27) (thickness 0.15)) (justify left bottom) hide)
    )
    (property "Author" "Antmicro" (at 100.33 88.9 0)
      (effects (font (size 1.27 1.27) (thickness 0.15)) (justify left bottom) hide)
    )
    (property "Voltage" "" (at 102.87 88.9 0)
      (effects (font (size 1.27 1.27)) (justify left bottom) hide)
    )
    (property "Dielectric" "" (at 105.41 88.9 0)
      (effects (font (size 1.27 1.27)) (justify left bottom) hide)
    )
    (property "Public" "False" (at 107.95 88.9 0)
      (effects (font (size 1.27 1.27)) (justify left bottom) hide)
    )
    (pin "1")
    (pin "2")
    (instances
      (project "ecp5-dc-scm"
        (path ""
          (reference "C174") (unit 1)
        )
      )
    )
  )

  (symbol (lib_id "antmicroCapacitors0402:C_470n_0402") (at 81.28 68.58 90) (mirror x) (unit 1)
    (in_bom yes) (on_board yes) (dnp no)
    (property "Reference" "C177" (at 80.645 69.85 90)
      (effects (font (size 1.524 1.524)) (justify left))
    )
    (property "Value" "C_470n_0402" (at 85.09 68.58 0)
      (effects (font (size 1.524 1.524)) hide)
    )
    (property "Footprint" "antmicro-footprints:C_0402_1005Metric" (at 76.2 73.66 0)
      (effects (font (size 1.524 1.524)) (justify left) hide)
    )
    (property "Datasheet" "https://product.tdk.com/en/search/capacitor/ceramic/mlcc/info?part_no=C1005X5R1E474M050BB" (at 81.28 68.58 0)
      (effects (font (size 1.27 1.27)) hide)
    )
    (property "Manufacturer" "TDK" (at 71.12 73.66 0)
      (effects (font (size 1.524 1.524)) (justify left) hide)
    )
    (property "MPN" "C1005X5R1E474M050BB" (at 73.66 73.66 0)
      (effects (font (size 1.524 1.524)) (justify left) hide)
    )
    (property "Val" "470n" (at 80.01 73.025 90)
      (effects (font (size 1.27 1.27)) (justify left))
    )
    (property "License" "Apache-2.0" (at 104.14 88.9 0)
      (effects (font (size 1.27 1.27) (thickness 0.15)) (justify left bottom) hide)
    )
    (property "Author" "Antmicro" (at 106.68 88.9 0)
      (effects (font (size 1.27 1.27) (thickness 0.15)) (justify left bottom) hide)
    )
    (property "Voltage" "" (at 109.22 88.9 0)
      (effects (font (size 1.27 1.27)) (justify left bottom) hide)
    )
    (property "Dielectric" "" (at 111.76 88.9 0)
      (effects (font (size 1.27 1.27)) (justify left bottom) hide)
    )
    (property "Public" "False" (at 114.3 88.9 0)
      (effects (font (size 1.27 1.27)) (justify left bottom) hide)
    )
    (pin "1")
    (pin "2")
    (instances
      (project "ecp5-dc-scm"
        (path ""
          (reference "C177") (unit 1)
        )
      )
    )
  )

  (symbol (lib_id "antmicroCapacitors0402:C_470n_0402") (at 87.63 68.58 90) (mirror x) (unit 1)
    (in_bom yes) (on_board yes) (dnp no)
    (property "Reference" "C181" (at 86.995 69.85 90)
      (effects (font (size 1.524 1.524)) (justify left))
    )
    (property "Value" "C_470n_0402" (at 91.44 68.58 0)
      (effects (font (size 1.524 1.524)) hide)
    )
    (property "Footprint" "antmicro-footprints:C_0402_1005Metric" (at 82.55 73.66 0)
      (effects (font (size 1.524 1.524)) (justify left) hide)
    )
    (property "Datasheet" "https://product.tdk.com/en/search/capacitor/ceramic/mlcc/info?part_no=C1005X5R1E474M050BB" (at 87.63 68.58 0)
      (effects (font (size 1.27 1.27)) hide)
    )
    (property "Manufacturer" "TDK" (at 77.47 73.66 0)
      (effects (font (size 1.524 1.524)) (justify left) hide)
    )
    (property "MPN" "C1005X5R1E474M050BB" (at 80.01 73.66 0)
      (effects (font (size 1.524 1.524)) (justify left) hide)
    )
    (property "Val" "470n" (at 86.36 73.025 90)
      (effects (font (size 1.27 1.27)) (justify left))
    )
    (property "License" "Apache-2.0" (at 110.49 88.9 0)
      (effects (font (size 1.27 1.27) (thickness 0.15)) (justify left bottom) hide)
    )
    (property "Author" "Antmicro" (at 113.03 88.9 0)
      (effects (font (size 1.27 1.27) (thickness 0.15)) (justify left bottom) hide)
    )
    (property "Voltage" "" (at 115.57 88.9 0)
      (effects (font (size 1.27 1.27)) (justify left bottom) hide)
    )
    (property "Dielectric" "" (at 118.11 88.9 0)
      (effects (font (size 1.27 1.27)) (justify left bottom) hide)
    )
    (property "Public" "False" (at 120.65 88.9 0)
      (effects (font (size 1.27 1.27)) (justify left bottom) hide)
    )
    (pin "1")
    (pin "2")
    (instances
      (project "ecp5-dc-scm"
        (path ""
          (reference "C181") (unit 1)
        )
      )
    )
  )

  (symbol (lib_id "antmicroCapacitors0402:C_470n_0402") (at 93.98 68.58 90) (mirror x) (unit 1)
    (in_bom yes) (on_board yes) (dnp no)
    (property "Reference" "C183" (at 93.345 69.85 90)
      (effects (font (size 1.524 1.524)) (justify left))
    )
    (property "Value" "C_470n_0402" (at 97.79 68.58 0)
      (effects (font (size 1.524 1.524)) hide)
    )
    (property "Footprint" "antmicro-footprints:C_0402_1005Metric" (at 88.9 73.66 0)
      (effects (font (size 1.524 1.524)) (justify left) hide)
    )
    (property "Datasheet" "https://product.tdk.com/en/search/capacitor/ceramic/mlcc/info?part_no=C1005X5R1E474M050BB" (at 93.98 68.58 0)
      (effects (font (size 1.27 1.27)) hide)
    )
    (property "Manufacturer" "TDK" (at 83.82 73.66 0)
      (effects (font (size 1.524 1.524)) (justify left) hide)
    )
    (property "MPN" "C1005X5R1E474M050BB" (at 86.36 73.66 0)
      (effects (font (size 1.524 1.524)) (justify left) hide)
    )
    (property "Val" "470n" (at 92.71 73.025 90)
      (effects (font (size 1.27 1.27)) (justify left))
    )
    (property "License" "Apache-2.0" (at 116.84 88.9 0)
      (effects (font (size 1.27 1.27) (thickness 0.15)) (justify left bottom) hide)
    )
    (property "Author" "Antmicro" (at 119.38 88.9 0)
      (effects (font (size 1.27 1.27) (thickness 0.15)) (justify left bottom) hide)
    )
    (property "Voltage" "" (at 121.92 88.9 0)
      (effects (font (size 1.27 1.27)) (justify left bottom) hide)
    )
    (property "Dielectric" "" (at 124.46 88.9 0)
      (effects (font (size 1.27 1.27)) (justify left bottom) hide)
    )
    (property "Public" "False" (at 127 88.9 0)
      (effects (font (size 1.27 1.27)) (justify left bottom) hide)
    )
    (pin "1")
    (pin "2")
    (instances
      (project "ecp5-dc-scm"
        (path ""
          (reference "C183") (unit 1)
        )
      )
    )
  )

  (symbol (lib_id "antmicroCapacitors0402:C_470n_0402") (at 100.33 68.58 90) (mirror x) (unit 1)
    (in_bom yes) (on_board yes) (dnp no)
    (property "Reference" "C185" (at 99.695 69.85 90)
      (effects (font (size 1.524 1.524)) (justify left))
    )
    (property "Value" "C_470n_0402" (at 104.14 68.58 0)
      (effects (font (size 1.524 1.524)) hide)
    )
    (property "Footprint" "antmicro-footprints:C_0402_1005Metric" (at 95.25 73.66 0)
      (effects (font (size 1.524 1.524)) (justify left) hide)
    )
    (property "Datasheet" "https://product.tdk.com/en/search/capacitor/ceramic/mlcc/info?part_no=C1005X5R1E474M050BB" (at 100.33 68.58 0)
      (effects (font (size 1.27 1.27)) hide)
    )
    (property "Manufacturer" "TDK" (at 90.17 73.66 0)
      (effects (font (size 1.524 1.524)) (justify left) hide)
    )
    (property "MPN" "C1005X5R1E474M050BB" (at 92.71 73.66 0)
      (effects (font (size 1.524 1.524)) (justify left) hide)
    )
    (property "Val" "470n" (at 99.695 73.025 90)
      (effects (font (size 1.27 1.27)) (justify left))
    )
    (property "License" "Apache-2.0" (at 123.19 88.9 0)
      (effects (font (size 1.27 1.27) (thickness 0.15)) (justify left bottom) hide)
    )
    (property "Author" "Antmicro" (at 125.73 88.9 0)
      (effects (font (size 1.27 1.27) (thickness 0.15)) (justify left bottom) hide)
    )
    (property "Voltage" "" (at 128.27 88.9 0)
      (effects (font (size 1.27 1.27)) (justify left bottom) hide)
    )
    (property "Dielectric" "" (at 130.81 88.9 0)
      (effects (font (size 1.27 1.27)) (justify left bottom) hide)
    )
    (property "Public" "False" (at 133.35 88.9 0)
      (effects (font (size 1.27 1.27)) (justify left bottom) hide)
    )
    (pin "1")
    (pin "2")
    (instances
      (project "ecp5-dc-scm"
        (path ""
          (reference "C185") (unit 1)
        )
      )
    )
  )

  (symbol (lib_id "antmicroCapacitors0402:C_470n_0402") (at 106.68 68.58 90) (mirror x) (unit 1)
    (in_bom yes) (on_board yes) (dnp no)
    (property "Reference" "C187" (at 106.045 69.85 90)
      (effects (font (size 1.524 1.524)) (justify left))
    )
    (property "Value" "C_470n_0402" (at 110.49 68.58 0)
      (effects (font (size 1.524 1.524)) hide)
    )
    (property "Footprint" "antmicro-footprints:C_0402_1005Metric" (at 101.6 73.66 0)
      (effects (font (size 1.524 1.524)) (justify left) hide)
    )
    (property "Datasheet" "https://product.tdk.com/en/search/capacitor/ceramic/mlcc/info?part_no=C1005X5R1E474M050BB" (at 106.68 68.58 0)
      (effects (font (size 1.27 1.27)) hide)
    )
    (property "Manufacturer" "TDK" (at 96.52 73.66 0)
      (effects (font (size 1.524 1.524)) (justify left) hide)
    )
    (property "MPN" "C1005X5R1E474M050BB" (at 99.06 73.66 0)
      (effects (font (size 1.524 1.524)) (justify left) hide)
    )
    (property "Val" "470n" (at 106.045 73.025 90)
      (effects (font (size 1.27 1.27)) (justify left))
    )
    (property "License" "Apache-2.0" (at 129.54 88.9 0)
      (effects (font (size 1.27 1.27) (thickness 0.15)) (justify left bottom) hide)
    )
    (property "Author" "Antmicro" (at 132.08 88.9 0)
      (effects (font (size 1.27 1.27) (thickness 0.15)) (justify left bottom) hide)
    )
    (property "Voltage" "" (at 134.62 88.9 0)
      (effects (font (size 1.27 1.27)) (justify left bottom) hide)
    )
    (property "Dielectric" "" (at 137.16 88.9 0)
      (effects (font (size 1.27 1.27)) (justify left bottom) hide)
    )
    (property "Public" "False" (at 139.7 88.9 0)
      (effects (font (size 1.27 1.27)) (justify left bottom) hide)
    )
    (pin "1")
    (pin "2")
    (instances
      (project "ecp5-dc-scm"
        (path ""
          (reference "C187") (unit 1)
        )
      )
    )
  )

  (symbol (lib_id "antmicroCapacitors0402:C_470n_0402") (at 113.03 68.58 90) (mirror x) (unit 1)
    (in_bom yes) (on_board yes) (dnp no)
    (property "Reference" "C188" (at 113.03 69.85 90)
      (effects (font (size 1.524 1.524)) (justify left))
    )
    (property "Value" "C_470n_0402" (at 116.84 68.58 0)
      (effects (font (size 1.524 1.524)) hide)
    )
    (property "Footprint" "antmicro-footprints:C_0402_1005Metric" (at 107.95 73.66 0)
      (effects (font (size 1.524 1.524)) (justify left) hide)
    )
    (property "Datasheet" "https://product.tdk.com/en/search/capacitor/ceramic/mlcc/info?part_no=C1005X5R1E474M050BB" (at 113.03 68.58 0)
      (effects (font (size 1.27 1.27)) hide)
    )
    (property "Manufacturer" "TDK" (at 102.87 73.66 0)
      (effects (font (size 1.524 1.524)) (justify left) hide)
    )
    (property "MPN" "C1005X5R1E474M050BB" (at 105.41 73.66 0)
      (effects (font (size 1.524 1.524)) (justify left) hide)
    )
    (property "Val" "470n" (at 113.03 73.025 90)
      (effects (font (size 1.27 1.27)) (justify left))
    )
    (property "License" "Apache-2.0" (at 135.89 88.9 0)
      (effects (font (size 1.27 1.27) (thickness 0.15)) (justify left bottom) hide)
    )
    (property "Author" "Antmicro" (at 138.43 88.9 0)
      (effects (font (size 1.27 1.27) (thickness 0.15)) (justify left bottom) hide)
    )
    (property "Voltage" "" (at 140.97 88.9 0)
      (effects (font (size 1.27 1.27)) (justify left bottom) hide)
    )
    (property "Dielectric" "" (at 143.51 88.9 0)
      (effects (font (size 1.27 1.27)) (justify left bottom) hide)
    )
    (property "Public" "False" (at 146.05 88.9 0)
      (effects (font (size 1.27 1.27)) (justify left bottom) hide)
    )
    (pin "1")
    (pin "2")
    (instances
      (project "ecp5-dc-scm"
        (path ""
          (reference "C188") (unit 1)
        )
      )
    )
  )

  (symbol (lib_id "antmicroCapacitors0402:C_470n_0402") (at 119.38 68.58 90) (mirror x) (unit 1)
    (in_bom yes) (on_board yes) (dnp no)
    (property "Reference" "C189" (at 118.745 69.85 90)
      (effects (font (size 1.524 1.524)) (justify left))
    )
    (property "Value" "C_470n_0402" (at 123.19 68.58 0)
      (effects (font (size 1.524 1.524)) hide)
    )
    (property "Footprint" "antmicro-footprints:C_0402_1005Metric" (at 114.3 73.66 0)
      (effects (font (size 1.524 1.524)) (justify left) hide)
    )
    (property "Datasheet" "https://product.tdk.com/en/search/capacitor/ceramic/mlcc/info?part_no=C1005X5R1E474M050BB" (at 119.38 68.58 0)
      (effects (font (size 1.27 1.27)) hide)
    )
    (property "Manufacturer" "TDK" (at 109.22 73.66 0)
      (effects (font (size 1.524 1.524)) (justify left) hide)
    )
    (property "MPN" "C1005X5R1E474M050BB" (at 111.76 73.66 0)
      (effects (font (size 1.524 1.524)) (justify left) hide)
    )
    (property "Val" "470n" (at 118.745 73.025 90)
      (effects (font (size 1.27 1.27)) (justify left))
    )
    (property "License" "Apache-2.0" (at 142.24 88.9 0)
      (effects (font (size 1.27 1.27) (thickness 0.15)) (justify left bottom) hide)
    )
    (property "Author" "Antmicro" (at 144.78 88.9 0)
      (effects (font (size 1.27 1.27) (thickness 0.15)) (justify left bottom) hide)
    )
    (property "Voltage" "" (at 147.32 88.9 0)
      (effects (font (size 1.27 1.27)) (justify left bottom) hide)
    )
    (property "Dielectric" "" (at 149.86 88.9 0)
      (effects (font (size 1.27 1.27)) (justify left bottom) hide)
    )
    (property "Public" "False" (at 152.4 88.9 0)
      (effects (font (size 1.27 1.27)) (justify left bottom) hide)
    )
    (pin "1")
    (pin "2")
    (instances
      (project "ecp5-dc-scm"
        (path ""
          (reference "C189") (unit 1)
        )
      )
    )
  )

  (symbol (lib_id "antmicroCapacitors0402:C_470n_0402") (at 125.73 68.58 90) (mirror x) (unit 1)
    (in_bom yes) (on_board yes) (dnp no)
    (property "Reference" "C190" (at 125.095 69.85 90)
      (effects (font (size 1.524 1.524)) (justify left))
    )
    (property "Value" "C_470n_0402" (at 129.54 68.58 0)
      (effects (font (size 1.524 1.524)) hide)
    )
    (property "Footprint" "antmicro-footprints:C_0402_1005Metric" (at 120.65 73.66 0)
      (effects (font (size 1.524 1.524)) (justify left) hide)
    )
    (property "Datasheet" "https://product.tdk.com/en/search/capacitor/ceramic/mlcc/info?part_no=C1005X5R1E474M050BB" (at 125.73 68.58 0)
      (effects (font (size 1.27 1.27)) hide)
    )
    (property "Manufacturer" "TDK" (at 115.57 73.66 0)
      (effects (font (size 1.524 1.524)) (justify left) hide)
    )
    (property "MPN" "C1005X5R1E474M050BB" (at 118.11 73.66 0)
      (effects (font (size 1.524 1.524)) (justify left) hide)
    )
    (property "Val" "470n" (at 125.095 73.025 90)
      (effects (font (size 1.27 1.27)) (justify left))
    )
    (property "License" "Apache-2.0" (at 148.59 88.9 0)
      (effects (font (size 1.27 1.27) (thickness 0.15)) (justify left bottom) hide)
    )
    (property "Author" "Antmicro" (at 151.13 88.9 0)
      (effects (font (size 1.27 1.27) (thickness 0.15)) (justify left bottom) hide)
    )
    (property "Voltage" "" (at 153.67 88.9 0)
      (effects (font (size 1.27 1.27)) (justify left bottom) hide)
    )
    (property "Dielectric" "" (at 156.21 88.9 0)
      (effects (font (size 1.27 1.27)) (justify left bottom) hide)
    )
    (property "Public" "False" (at 158.75 88.9 0)
      (effects (font (size 1.27 1.27)) (justify left bottom) hide)
    )
    (pin "1")
    (pin "2")
    (instances
      (project "ecp5-dc-scm"
        (path ""
          (reference "C190") (unit 1)
        )
      )
    )
  )

  (symbol (lib_id "antmicroCapacitors0402:C_470n_0402") (at 132.08 68.58 90) (mirror x) (unit 1)
    (in_bom yes) (on_board yes) (dnp no)
    (property "Reference" "C191" (at 131.445 69.85 90)
      (effects (font (size 1.524 1.524)) (justify left))
    )
    (property "Value" "C_470n_0402" (at 135.89 68.58 0)
      (effects (font (size 1.524 1.524)) hide)
    )
    (property "Footprint" "antmicro-footprints:C_0402_1005Metric" (at 127 73.66 0)
      (effects (font (size 1.524 1.524)) (justify left) hide)
    )
    (property "Datasheet" "https://product.tdk.com/en/search/capacitor/ceramic/mlcc/info?part_no=C1005X5R1E474M050BB" (at 132.08 68.58 0)
      (effects (font (size 1.27 1.27)) hide)
    )
    (property "Manufacturer" "TDK" (at 121.92 73.66 0)
      (effects (font (size 1.524 1.524)) (justify left) hide)
    )
    (property "MPN" "C1005X5R1E474M050BB" (at 124.46 73.66 0)
      (effects (font (size 1.524 1.524)) (justify left) hide)
    )
    (property "Val" "470n" (at 131.445 73.025 90)
      (effects (font (size 1.27 1.27)) (justify left))
    )
    (property "License" "Apache-2.0" (at 154.94 88.9 0)
      (effects (font (size 1.27 1.27) (thickness 0.15)) (justify left bottom) hide)
    )
    (property "Author" "Antmicro" (at 157.48 88.9 0)
      (effects (font (size 1.27 1.27) (thickness 0.15)) (justify left bottom) hide)
    )
    (property "Voltage" "" (at 160.02 88.9 0)
      (effects (font (size 1.27 1.27)) (justify left bottom) hide)
    )
    (property "Dielectric" "" (at 162.56 88.9 0)
      (effects (font (size 1.27 1.27)) (justify left bottom) hide)
    )
    (property "Public" "False" (at 165.1 88.9 0)
      (effects (font (size 1.27 1.27)) (justify left bottom) hide)
    )
    (pin "1")
    (pin "2")
    (instances
      (project "ecp5-dc-scm"
        (path ""
          (reference "C191") (unit 1)
        )
      )
    )
  )

  (symbol (lib_id "antmicroCapacitors0402:C_470n_0402") (at 138.43 68.58 90) (mirror x) (unit 1)
    (in_bom yes) (on_board yes) (dnp no)
    (property "Reference" "C192" (at 137.795 69.85 90)
      (effects (font (size 1.524 1.524)) (justify left))
    )
    (property "Value" "C_470n_0402" (at 142.24 68.58 0)
      (effects (font (size 1.524 1.524)) hide)
    )
    (property "Footprint" "antmicro-footprints:C_0402_1005Metric" (at 133.35 73.66 0)
      (effects (font (size 1.524 1.524)) (justify left) hide)
    )
    (property "Datasheet" "https://product.tdk.com/en/search/capacitor/ceramic/mlcc/info?part_no=C1005X5R1E474M050BB" (at 138.43 68.58 0)
      (effects (font (size 1.27 1.27)) hide)
    )
    (property "Manufacturer" "TDK" (at 128.27 73.66 0)
      (effects (font (size 1.524 1.524)) (justify left) hide)
    )
    (property "MPN" "C1005X5R1E474M050BB" (at 130.81 73.66 0)
      (effects (font (size 1.524 1.524)) (justify left) hide)
    )
    (property "Val" "470n" (at 137.795 73.025 90)
      (effects (font (size 1.27 1.27)) (justify left))
    )
    (property "License" "Apache-2.0" (at 161.29 88.9 0)
      (effects (font (size 1.27 1.27) (thickness 0.15)) (justify left bottom) hide)
    )
    (property "Author" "Antmicro" (at 163.83 88.9 0)
      (effects (font (size 1.27 1.27) (thickness 0.15)) (justify left bottom) hide)
    )
    (property "Voltage" "" (at 166.37 88.9 0)
      (effects (font (size 1.27 1.27)) (justify left bottom) hide)
    )
    (property "Dielectric" "" (at 168.91 88.9 0)
      (effects (font (size 1.27 1.27)) (justify left bottom) hide)
    )
    (property "Public" "False" (at 171.45 88.9 0)
      (effects (font (size 1.27 1.27)) (justify left bottom) hide)
    )
    (pin "1")
    (pin "2")
    (instances
      (project "ecp5-dc-scm"
        (path ""
          (reference "C192") (unit 1)
        )
      )
    )
  )

  (symbol (lib_id "antmicroCapacitors0402:C_470n_0402") (at 144.78 68.58 90) (mirror x) (unit 1)
    (in_bom yes) (on_board yes) (dnp no)
    (property "Reference" "C193" (at 144.145 69.85 90)
      (effects (font (size 1.524 1.524)) (justify left))
    )
    (property "Value" "C_470n_0402" (at 148.59 68.58 0)
      (effects (font (size 1.524 1.524)) hide)
    )
    (property "Footprint" "antmicro-footprints:C_0402_1005Metric" (at 139.7 73.66 0)
      (effects (font (size 1.524 1.524)) (justify left) hide)
    )
    (property "Datasheet" "https://product.tdk.com/en/search/capacitor/ceramic/mlcc/info?part_no=C1005X5R1E474M050BB" (at 144.78 68.58 0)
      (effects (font (size 1.27 1.27)) hide)
    )
    (property "Manufacturer" "TDK" (at 134.62 73.66 0)
      (effects (font (size 1.524 1.524)) (justify left) hide)
    )
    (property "MPN" "C1005X5R1E474M050BB" (at 137.16 73.66 0)
      (effects (font (size 1.524 1.524)) (justify left) hide)
    )
    (property "Val" "470n" (at 144.145 73.025 90)
      (effects (font (size 1.27 1.27)) (justify left))
    )
    (property "License" "Apache-2.0" (at 167.64 88.9 0)
      (effects (font (size 1.27 1.27) (thickness 0.15)) (justify left bottom) hide)
    )
    (property "Author" "Antmicro" (at 170.18 88.9 0)
      (effects (font (size 1.27 1.27) (thickness 0.15)) (justify left bottom) hide)
    )
    (property "Voltage" "" (at 172.72 88.9 0)
      (effects (font (size 1.27 1.27)) (justify left bottom) hide)
    )
    (property "Dielectric" "" (at 175.26 88.9 0)
      (effects (font (size 1.27 1.27)) (justify left bottom) hide)
    )
    (property "Public" "False" (at 177.8 88.9 0)
      (effects (font (size 1.27 1.27)) (justify left bottom) hide)
    )
    (pin "1")
    (pin "2")
    (instances
      (project "ecp5-dc-scm"
        (path ""
          (reference "C193") (unit 1)
        )
      )
    )
  )

  (symbol (lib_id "antmicroCapacitors0402:C_4u7_0402") (at 125.73 172.72 270) (mirror x) (unit 1)
    (in_bom yes) (on_board yes) (dnp no)
    (property "Reference" "C158" (at 128.27 172.085 0)
      (effects (font (size 1.524 1.524)) (justify left))
    )
    (property "Value" "C_4u7_0402" (at 121.92 172.72 0)
      (effects (font (size 1.524 1.524)) hide)
    )
    (property "Footprint" "antmicro-footprints:C_0402_1005Metric" (at 130.81 167.64 0)
      (effects (font (size 1.524 1.524)) (justify left) hide)
    )
    (property "Datasheet" "https://www.murata.com/products/productdetail?partno=GRM155R61A475MEAA%23" (at 125.73 172.72 0)
      (effects (font (size 1.27 1.27)) hide)
    )
    (property "Manufacturer" "Murata" (at 135.89 167.64 0)
      (effects (font (size 1.524 1.524)) (justify left) hide)
    )
    (property "MPN" "GRM155R61A475MEAAD" (at 133.35 167.64 0)
      (effects (font (size 1.524 1.524)) (justify left) hide)
    )
    (property "Val" "4u7" (at 123.19 172.085 0)
      (effects (font (size 1.27 1.27)) (justify left))
    )
    (property "License" "Apache-2.0" (at 102.87 152.4 0)
      (effects (font (size 1.27 1.27) (thickness 0.15)) (justify left bottom) hide)
    )
    (property "Author" "Antmicro" (at 100.33 152.4 0)
      (effects (font (size 1.27 1.27) (thickness 0.15)) (justify left bottom) hide)
    )
    (property "Voltage" "" (at 97.79 152.4 0)
      (effects (font (size 1.27 1.27)) (justify left bottom) hide)
    )
    (property "Dielectric" "" (at 95.25 152.4 0)
      (effects (font (size 1.27 1.27)) (justify left bottom) hide)
    )
    (property "Public" "False" (at 92.71 152.4 0)
      (effects (font (size 1.27 1.27)) (justify left bottom) hide)
    )
    (pin "1")
    (pin "2")
    (instances
      (project "ecp5-dc-scm"
        (path ""
          (reference "C158") (unit 1)
        )
      )
    )
  )

  (symbol (lib_id "antmicroCapacitors0603:C_47u_0603") (at 132.08 172.72 270) (mirror x) (unit 1)
    (in_bom yes) (on_board yes) (dnp no)
    (property "Reference" "C155" (at 134.62 172.085 0)
      (effects (font (size 1.524 1.524)) (justify left))
    )
    (property "Value" "C_47u_0603" (at 128.27 172.72 0)
      (effects (font (size 1.524 1.524)) hide)
    )
    (property "Footprint" "antmicro-footprints:C_0603_1608Metric" (at 137.16 167.64 0)
      (effects (font (size 1.524 1.524)) (justify left) hide)
    )
    (property "Datasheet" "https://www.murata.com/products/productdetail?partno=GRM188R60J476ME15%23" (at 132.08 172.72 0)
      (effects (font (size 1.27 1.27)) hide)
    )
    (property "Manufacturer" "Murata" (at 142.24 167.64 0)
      (effects (font (size 1.524 1.524)) (justify left) hide)
    )
    (property "MPN" "GRM188R60J476ME15D" (at 139.7 167.64 0)
      (effects (font (size 1.524 1.524)) (justify left) hide)
    )
    (property "Val" "47u" (at 129.54 172.085 0)
      (effects (font (size 1.27 1.27)) (justify left))
    )
    (property "License" "Apache-2.0" (at 109.22 152.4 0)
      (effects (font (size 1.27 1.27) (thickness 0.15)) (justify left bottom) hide)
    )
    (property "Author" "Antmicro" (at 106.68 152.4 0)
      (effects (font (size 1.27 1.27) (thickness 0.15)) (justify left bottom) hide)
    )
    (property "Voltage" "" (at 104.14 152.4 0)
      (effects (font (size 1.27 1.27)) (justify left bottom) hide)
    )
    (property "Dielectric" "" (at 101.6 152.4 0)
      (effects (font (size 1.27 1.27)) (justify left bottom) hide)
    )
    (property "Public" "False" (at 99.06 152.4 0)
      (effects (font (size 1.27 1.27)) (justify left bottom) hide)
    )
    (pin "1")
    (pin "2")
    (instances
      (project "ecp5-dc-scm"
        (path ""
          (reference "C155") (unit 1)
        )
      )
    )
  )

  (symbol (lib_id "antmicroCapacitors0402:C_470n_0402") (at 119.38 172.72 270) (mirror x) (unit 1)
    (in_bom yes) (on_board yes) (dnp no)
    (property "Reference" "C161" (at 121.92 172.085 0)
      (effects (font (size 1.524 1.524)) (justify left))
    )
    (property "Value" "C_470n_0402" (at 115.57 172.72 0)
      (effects (font (size 1.524 1.524)) hide)
    )
    (property "Footprint" "antmicro-footprints:C_0402_1005Metric" (at 124.46 167.64 0)
      (effects (font (size 1.524 1.524)) (justify left) hide)
    )
    (property "Datasheet" "https://product.tdk.com/en/search/capacitor/ceramic/mlcc/info?part_no=C1005X5R1E474M050BB" (at 119.38 172.72 0)
      (effects (font (size 1.27 1.27)) hide)
    )
    (property "Manufacturer" "TDK" (at 129.54 167.64 0)
      (effects (font (size 1.524 1.524)) (justify left) hide)
    )
    (property "MPN" "C1005X5R1E474M050BB" (at 127 167.64 0)
      (effects (font (size 1.524 1.524)) (justify left) hide)
    )
    (property "Val" "470n" (at 116.84 172.085 0)
      (effects (font (size 1.27 1.27)) (justify left))
    )
    (property "License" "Apache-2.0" (at 96.52 152.4 0)
      (effects (font (size 1.27 1.27) (thickness 0.15)) (justify left bottom) hide)
    )
    (property "Author" "Antmicro" (at 93.98 152.4 0)
      (effects (font (size 1.27 1.27) (thickness 0.15)) (justify left bottom) hide)
    )
    (property "Voltage" "" (at 91.44 152.4 0)
      (effects (font (size 1.27 1.27)) (justify left bottom) hide)
    )
    (property "Dielectric" "" (at 88.9 152.4 0)
      (effects (font (size 1.27 1.27)) (justify left bottom) hide)
    )
    (property "Public" "False" (at 86.36 152.4 0)
      (effects (font (size 1.27 1.27)) (justify left bottom) hide)
    )
    (pin "1")
    (pin "2")
    (instances
      (project "ecp5-dc-scm"
        (path ""
          (reference "C161") (unit 1)
        )
      )
    )
  )

  (symbol (lib_id "antmicroCapacitors0402:C_470n_0402") (at 113.03 172.72 270) (mirror x) (unit 1)
    (in_bom yes) (on_board yes) (dnp no)
    (property "Reference" "C164" (at 115.57 172.085 0)
      (effects (font (size 1.524 1.524)) (justify left))
    )
    (property "Value" "C_470n_0402" (at 109.22 172.72 0)
      (effects (font (size 1.524 1.524)) hide)
    )
    (property "Footprint" "antmicro-footprints:C_0402_1005Metric" (at 118.11 167.64 0)
      (effects (font (size 1.524 1.524)) (justify left) hide)
    )
    (property "Datasheet" "https://product.tdk.com/en/search/capacitor/ceramic/mlcc/info?part_no=C1005X5R1E474M050BB" (at 113.03 172.72 0)
      (effects (font (size 1.27 1.27)) hide)
    )
    (property "Manufacturer" "TDK" (at 123.19 167.64 0)
      (effects (font (size 1.524 1.524)) (justify left) hide)
    )
    (property "MPN" "C1005X5R1E474M050BB" (at 120.65 167.64 0)
      (effects (font (size 1.524 1.524)) (justify left) hide)
    )
    (property "Val" "470n" (at 110.49 172.085 0)
      (effects (font (size 1.27 1.27)) (justify left))
    )
    (property "License" "Apache-2.0" (at 90.17 152.4 0)
      (effects (font (size 1.27 1.27) (thickness 0.15)) (justify left bottom) hide)
    )
    (property "Author" "Antmicro" (at 87.63 152.4 0)
      (effects (font (size 1.27 1.27) (thickness 0.15)) (justify left bottom) hide)
    )
    (property "Voltage" "" (at 85.09 152.4 0)
      (effects (font (size 1.27 1.27)) (justify left bottom) hide)
    )
    (property "Dielectric" "" (at 82.55 152.4 0)
      (effects (font (size 1.27 1.27)) (justify left bottom) hide)
    )
    (property "Public" "False" (at 80.01 152.4 0)
      (effects (font (size 1.27 1.27)) (justify left bottom) hide)
    )
    (pin "1")
    (pin "2")
    (instances
      (project "ecp5-dc-scm"
        (path ""
          (reference "C164") (unit 1)
        )
      )
    )
  )

  (symbol (lib_id "antmicroCapacitors0402:C_470n_0402") (at 106.68 172.72 270) (mirror x) (unit 1)
    (in_bom yes) (on_board yes) (dnp no)
    (property "Reference" "C167" (at 109.22 172.085 0)
      (effects (font (size 1.524 1.524)) (justify left))
    )
    (property "Value" "C_470n_0402" (at 102.87 172.72 0)
      (effects (font (size 1.524 1.524)) hide)
    )
    (property "Footprint" "antmicro-footprints:C_0402_1005Metric" (at 111.76 167.64 0)
      (effects (font (size 1.524 1.524)) (justify left) hide)
    )
    (property "Datasheet" "https://product.tdk.com/en/search/capacitor/ceramic/mlcc/info?part_no=C1005X5R1E474M050BB" (at 106.68 172.72 0)
      (effects (font (size 1.27 1.27)) hide)
    )
    (property "Manufacturer" "TDK" (at 116.84 167.64 0)
      (effects (font (size 1.524 1.524)) (justify left) hide)
    )
    (property "MPN" "C1005X5R1E474M050BB" (at 114.3 167.64 0)
      (effects (font (size 1.524 1.524)) (justify left) hide)
    )
    (property "Val" "470n" (at 104.14 172.085 0)
      (effects (font (size 1.27 1.27)) (justify left))
    )
    (property "License" "Apache-2.0" (at 83.82 152.4 0)
      (effects (font (size 1.27 1.27) (thickness 0.15)) (justify left bottom) hide)
    )
    (property "Author" "Antmicro" (at 81.28 152.4 0)
      (effects (font (size 1.27 1.27) (thickness 0.15)) (justify left bottom) hide)
    )
    (property "Voltage" "" (at 78.74 152.4 0)
      (effects (font (size 1.27 1.27)) (justify left bottom) hide)
    )
    (property "Dielectric" "" (at 76.2 152.4 0)
      (effects (font (size 1.27 1.27)) (justify left bottom) hide)
    )
    (property "Public" "False" (at 73.66 152.4 0)
      (effects (font (size 1.27 1.27)) (justify left bottom) hide)
    )
    (pin "1")
    (pin "2")
    (instances
      (project "ecp5-dc-scm"
        (path ""
          (reference "C167") (unit 1)
        )
      )
    )
  )

  (symbol (lib_id "antmicroCapacitors0402:C_470n_0402") (at 100.33 172.72 270) (mirror x) (unit 1)
    (in_bom yes) (on_board yes) (dnp no)
    (property "Reference" "C170" (at 102.87 172.085 0)
      (effects (font (size 1.524 1.524)) (justify left))
    )
    (property "Value" "C_470n_0402" (at 96.52 172.72 0)
      (effects (font (size 1.524 1.524)) hide)
    )
    (property "Footprint" "antmicro-footprints:C_0402_1005Metric" (at 105.41 167.64 0)
      (effects (font (size 1.524 1.524)) (justify left) hide)
    )
    (property "Datasheet" "https://product.tdk.com/en/search/capacitor/ceramic/mlcc/info?part_no=C1005X5R1E474M050BB" (at 100.33 172.72 0)
      (effects (font (size 1.27 1.27)) hide)
    )
    (property "Manufacturer" "TDK" (at 110.49 167.64 0)
      (effects (font (size 1.524 1.524)) (justify left) hide)
    )
    (property "MPN" "C1005X5R1E474M050BB" (at 107.95 167.64 0)
      (effects (font (size 1.524 1.524)) (justify left) hide)
    )
    (property "Val" "470n" (at 97.79 172.085 0)
      (effects (font (size 1.27 1.27)) (justify left))
    )
    (property "License" "Apache-2.0" (at 77.47 152.4 0)
      (effects (font (size 1.27 1.27) (thickness 0.15)) (justify left bottom) hide)
    )
    (property "Author" "Antmicro" (at 74.93 152.4 0)
      (effects (font (size 1.27 1.27) (thickness 0.15)) (justify left bottom) hide)
    )
    (property "Voltage" "" (at 72.39 152.4 0)
      (effects (font (size 1.27 1.27)) (justify left bottom) hide)
    )
    (property "Dielectric" "" (at 69.85 152.4 0)
      (effects (font (size 1.27 1.27)) (justify left bottom) hide)
    )
    (property "Public" "False" (at 67.31 152.4 0)
      (effects (font (size 1.27 1.27)) (justify left bottom) hide)
    )
    (pin "1")
    (pin "2")
    (instances
      (project "ecp5-dc-scm"
        (path ""
          (reference "C170") (unit 1)
        )
      )
    )
  )

  (symbol (lib_id "antmicroCapacitors0402:C_470n_0402") (at 93.98 172.72 270) (mirror x) (unit 1)
    (in_bom yes) (on_board yes) (dnp no)
    (property "Reference" "C173" (at 96.52 172.085 0)
      (effects (font (size 1.524 1.524)) (justify left))
    )
    (property "Value" "C_470n_0402" (at 90.17 172.72 0)
      (effects (font (size 1.524 1.524)) hide)
    )
    (property "Footprint" "antmicro-footprints:C_0402_1005Metric" (at 99.06 167.64 0)
      (effects (font (size 1.524 1.524)) (justify left) hide)
    )
    (property "Datasheet" "https://product.tdk.com/en/search/capacitor/ceramic/mlcc/info?part_no=C1005X5R1E474M050BB" (at 93.98 172.72 0)
      (effects (font (size 1.27 1.27)) hide)
    )
    (property "Manufacturer" "TDK" (at 104.14 167.64 0)
      (effects (font (size 1.524 1.524)) (justify left) hide)
    )
    (property "MPN" "C1005X5R1E474M050BB" (at 101.6 167.64 0)
      (effects (font (size 1.524 1.524)) (justify left) hide)
    )
    (property "Val" "470n" (at 91.44 172.085 0)
      (effects (font (size 1.27 1.27)) (justify left))
    )
    (property "License" "Apache-2.0" (at 71.12 152.4 0)
      (effects (font (size 1.27 1.27) (thickness 0.15)) (justify left bottom) hide)
    )
    (property "Author" "Antmicro" (at 68.58 152.4 0)
      (effects (font (size 1.27 1.27) (thickness 0.15)) (justify left bottom) hide)
    )
    (property "Voltage" "" (at 66.04 152.4 0)
      (effects (font (size 1.27 1.27)) (justify left bottom) hide)
    )
    (property "Dielectric" "" (at 63.5 152.4 0)
      (effects (font (size 1.27 1.27)) (justify left bottom) hide)
    )
    (property "Public" "False" (at 60.96 152.4 0)
      (effects (font (size 1.27 1.27)) (justify left bottom) hide)
    )
    (pin "1")
    (pin "2")
    (instances
      (project "ecp5-dc-scm"
        (path ""
          (reference "C173") (unit 1)
        )
      )
    )
  )

  (symbol (lib_id "antmicroCapacitors0402:C_470n_0402") (at 87.63 172.72 270) (mirror x) (unit 1)
    (in_bom yes) (on_board yes) (dnp no)
    (property "Reference" "C176" (at 90.17 172.085 0)
      (effects (font (size 1.524 1.524)) (justify left))
    )
    (property "Value" "C_470n_0402" (at 83.82 172.72 0)
      (effects (font (size 1.524 1.524)) hide)
    )
    (property "Footprint" "antmicro-footprints:C_0402_1005Metric" (at 92.71 167.64 0)
      (effects (font (size 1.524 1.524)) (justify left) hide)
    )
    (property "Datasheet" "https://product.tdk.com/en/search/capacitor/ceramic/mlcc/info?part_no=C1005X5R1E474M050BB" (at 87.63 172.72 0)
      (effects (font (size 1.27 1.27)) hide)
    )
    (property "Manufacturer" "TDK" (at 97.79 167.64 0)
      (effects (font (size 1.524 1.524)) (justify left) hide)
    )
    (property "MPN" "C1005X5R1E474M050BB" (at 95.25 167.64 0)
      (effects (font (size 1.524 1.524)) (justify left) hide)
    )
    (property "Val" "470n" (at 85.09 172.085 0)
      (effects (font (size 1.27 1.27)) (justify left))
    )
    (property "License" "Apache-2.0" (at 64.77 152.4 0)
      (effects (font (size 1.27 1.27) (thickness 0.15)) (justify left bottom) hide)
    )
    (property "Author" "Antmicro" (at 62.23 152.4 0)
      (effects (font (size 1.27 1.27) (thickness 0.15)) (justify left bottom) hide)
    )
    (property "Voltage" "" (at 59.69 152.4 0)
      (effects (font (size 1.27 1.27)) (justify left bottom) hide)
    )
    (property "Dielectric" "" (at 57.15 152.4 0)
      (effects (font (size 1.27 1.27)) (justify left bottom) hide)
    )
    (property "Public" "False" (at 54.61 152.4 0)
      (effects (font (size 1.27 1.27)) (justify left bottom) hide)
    )
    (pin "1")
    (pin "2")
    (instances
      (project "ecp5-dc-scm"
        (path ""
          (reference "C176") (unit 1)
        )
      )
    )
  )

  (symbol (lib_id "antmicroCapacitors0402:C_470n_0402") (at 81.28 172.72 270) (mirror x) (unit 1)
    (in_bom yes) (on_board yes) (dnp no)
    (property "Reference" "C179" (at 83.82 172.085 0)
      (effects (font (size 1.524 1.524)) (justify left))
    )
    (property "Value" "C_470n_0402" (at 77.47 172.72 0)
      (effects (font (size 1.524 1.524)) hide)
    )
    (property "Footprint" "antmicro-footprints:C_0402_1005Metric" (at 86.36 167.64 0)
      (effects (font (size 1.524 1.524)) (justify left) hide)
    )
    (property "Datasheet" "https://product.tdk.com/en/search/capacitor/ceramic/mlcc/info?part_no=C1005X5R1E474M050BB" (at 81.28 172.72 0)
      (effects (font (size 1.27 1.27)) hide)
    )
    (property "Manufacturer" "TDK" (at 91.44 167.64 0)
      (effects (font (size 1.524 1.524)) (justify left) hide)
    )
    (property "MPN" "C1005X5R1E474M050BB" (at 88.9 167.64 0)
      (effects (font (size 1.524 1.524)) (justify left) hide)
    )
    (property "Val" "470n" (at 78.74 172.085 0)
      (effects (font (size 1.27 1.27)) (justify left))
    )
    (property "License" "Apache-2.0" (at 58.42 152.4 0)
      (effects (font (size 1.27 1.27) (thickness 0.15)) (justify left bottom) hide)
    )
    (property "Author" "Antmicro" (at 55.88 152.4 0)
      (effects (font (size 1.27 1.27) (thickness 0.15)) (justify left bottom) hide)
    )
    (property "Voltage" "" (at 53.34 152.4 0)
      (effects (font (size 1.27 1.27)) (justify left bottom) hide)
    )
    (property "Dielectric" "" (at 50.8 152.4 0)
      (effects (font (size 1.27 1.27)) (justify left bottom) hide)
    )
    (property "Public" "False" (at 48.26 152.4 0)
      (effects (font (size 1.27 1.27)) (justify left bottom) hide)
    )
    (pin "1")
    (pin "2")
    (instances
      (project "ecp5-dc-scm"
        (path ""
          (reference "C179") (unit 1)
        )
      )
    )
  )

  (symbol (lib_id "antmicroCapacitors0402:C_470n_0402") (at 74.93 172.72 270) (mirror x) (unit 1)
    (in_bom yes) (on_board yes) (dnp no)
    (property "Reference" "C182" (at 77.47 172.085 0)
      (effects (font (size 1.524 1.524)) (justify left))
    )
    (property "Value" "C_470n_0402" (at 71.12 172.72 0)
      (effects (font (size 1.524 1.524)) hide)
    )
    (property "Footprint" "antmicro-footprints:C_0402_1005Metric" (at 80.01 167.64 0)
      (effects (font (size 1.524 1.524)) (justify left) hide)
    )
    (property "Datasheet" "https://product.tdk.com/en/search/capacitor/ceramic/mlcc/info?part_no=C1005X5R1E474M050BB" (at 74.93 172.72 0)
      (effects (font (size 1.27 1.27)) hide)
    )
    (property "Manufacturer" "TDK" (at 85.09 167.64 0)
      (effects (font (size 1.524 1.524)) (justify left) hide)
    )
    (property "MPN" "C1005X5R1E474M050BB" (at 82.55 167.64 0)
      (effects (font (size 1.524 1.524)) (justify left) hide)
    )
    (property "Val" "470n" (at 72.39 172.085 0)
      (effects (font (size 1.27 1.27)) (justify left))
    )
    (property "License" "Apache-2.0" (at 52.07 152.4 0)
      (effects (font (size 1.27 1.27) (thickness 0.15)) (justify left bottom) hide)
    )
    (property "Author" "Antmicro" (at 49.53 152.4 0)
      (effects (font (size 1.27 1.27) (thickness 0.15)) (justify left bottom) hide)
    )
    (property "Voltage" "" (at 46.99 152.4 0)
      (effects (font (size 1.27 1.27)) (justify left bottom) hide)
    )
    (property "Dielectric" "" (at 44.45 152.4 0)
      (effects (font (size 1.27 1.27)) (justify left bottom) hide)
    )
    (property "Public" "False" (at 41.91 152.4 0)
      (effects (font (size 1.27 1.27)) (justify left bottom) hide)
    )
    (pin "1")
    (pin "2")
    (instances
      (project "ecp5-dc-scm"
        (path ""
          (reference "C182") (unit 1)
        )
      )
    )
  )

  (symbol (lib_id "antmicroCapacitors0402:C_4u7_0402") (at 107.95 135.89 270) (mirror x) (unit 1)
    (in_bom yes) (on_board yes) (dnp no)
    (property "Reference" "C160" (at 110.49 135.255 0)
      (effects (font (size 1.524 1.524)) (justify left))
    )
    (property "Value" "C_4u7_0402" (at 104.14 135.89 0)
      (effects (font (size 1.524 1.524)) hide)
    )
    (property "Footprint" "antmicro-footprints:C_0402_1005Metric" (at 113.03 130.81 0)
      (effects (font (size 1.524 1.524)) (justify left) hide)
    )
    (property "Datasheet" "https://www.murata.com/products/productdetail?partno=GRM155R61A475MEAA%23" (at 107.95 135.89 0)
      (effects (font (size 1.27 1.27)) hide)
    )
    (property "Manufacturer" "Murata" (at 118.11 130.81 0)
      (effects (font (size 1.524 1.524)) (justify left) hide)
    )
    (property "MPN" "GRM155R61A475MEAAD" (at 115.57 130.81 0)
      (effects (font (size 1.524 1.524)) (justify left) hide)
    )
    (property "Val" "4u7" (at 105.41 135.255 0)
      (effects (font (size 1.27 1.27)) (justify left))
    )
    (property "License" "Apache-2.0" (at 85.09 115.57 0)
      (effects (font (size 1.27 1.27) (thickness 0.15)) (justify left bottom) hide)
    )
    (property "Author" "Antmicro" (at 82.55 115.57 0)
      (effects (font (size 1.27 1.27) (thickness 0.15)) (justify left bottom) hide)
    )
    (property "Voltage" "" (at 80.01 115.57 0)
      (effects (font (size 1.27 1.27)) (justify left bottom) hide)
    )
    (property "Dielectric" "" (at 77.47 115.57 0)
      (effects (font (size 1.27 1.27)) (justify left bottom) hide)
    )
    (property "Public" "False" (at 74.93 115.57 0)
      (effects (font (size 1.27 1.27)) (justify left bottom) hide)
    )
    (pin "1")
    (pin "2")
    (instances
      (project "ecp5-dc-scm"
        (path ""
          (reference "C160") (unit 1)
        )
      )
    )
  )

  (symbol (lib_id "antmicroCapacitors0603:C_47u_0603") (at 114.3 135.89 270) (mirror x) (unit 1)
    (in_bom yes) (on_board yes) (dnp no)
    (property "Reference" "C157" (at 116.84 135.255 0)
      (effects (font (size 1.524 1.524)) (justify left))
    )
    (property "Value" "C_47u_0603" (at 110.49 135.89 0)
      (effects (font (size 1.524 1.524)) hide)
    )
    (property "Footprint" "antmicro-footprints:C_0603_1608Metric" (at 119.38 130.81 0)
      (effects (font (size 1.524 1.524)) (justify left) hide)
    )
    (property "Datasheet" "https://www.murata.com/products/productdetail?partno=GRM188R60J476ME15%23" (at 114.3 135.89 0)
      (effects (font (size 1.27 1.27)) hide)
    )
    (property "Manufacturer" "Murata" (at 124.46 130.81 0)
      (effects (font (size 1.524 1.524)) (justify left) hide)
    )
    (property "MPN" "GRM188R60J476ME15D" (at 121.92 130.81 0)
      (effects (font (size 1.524 1.524)) (justify left) hide)
    )
    (property "Val" "47u" (at 111.76 135.255 0)
      (effects (font (size 1.27 1.27)) (justify left))
    )
    (property "License" "Apache-2.0" (at 91.44 115.57 0)
      (effects (font (size 1.27 1.27) (thickness 0.15)) (justify left bottom) hide)
    )
    (property "Author" "Antmicro" (at 88.9 115.57 0)
      (effects (font (size 1.27 1.27) (thickness 0.15)) (justify left bottom) hide)
    )
    (property "Voltage" "" (at 86.36 115.57 0)
      (effects (font (size 1.27 1.27)) (justify left bottom) hide)
    )
    (property "Dielectric" "" (at 83.82 115.57 0)
      (effects (font (size 1.27 1.27)) (justify left bottom) hide)
    )
    (property "Public" "False" (at 81.28 115.57 0)
      (effects (font (size 1.27 1.27)) (justify left bottom) hide)
    )
    (pin "1")
    (pin "2")
    (instances
      (project "ecp5-dc-scm"
        (path ""
          (reference "C157") (unit 1)
        )
      )
    )
  )

  (symbol (lib_id "antmicroCapacitors0402:C_470n_0402") (at 101.6 135.89 270) (mirror x) (unit 1)
    (in_bom yes) (on_board yes) (dnp no)
    (property "Reference" "C163" (at 104.14 135.255 0)
      (effects (font (size 1.524 1.524)) (justify left))
    )
    (property "Value" "C_470n_0402" (at 97.79 135.89 0)
      (effects (font (size 1.524 1.524)) hide)
    )
    (property "Footprint" "antmicro-footprints:C_0402_1005Metric" (at 106.68 130.81 0)
      (effects (font (size 1.524 1.524)) (justify left) hide)
    )
    (property "Datasheet" "https://product.tdk.com/en/search/capacitor/ceramic/mlcc/info?part_no=C1005X5R1E474M050BB" (at 101.6 135.89 0)
      (effects (font (size 1.27 1.27)) hide)
    )
    (property "Manufacturer" "TDK" (at 111.76 130.81 0)
      (effects (font (size 1.524 1.524)) (justify left) hide)
    )
    (property "MPN" "C1005X5R1E474M050BB" (at 109.22 130.81 0)
      (effects (font (size 1.524 1.524)) (justify left) hide)
    )
    (property "Val" "470n" (at 99.06 135.255 0)
      (effects (font (size 1.27 1.27)) (justify left))
    )
    (property "License" "Apache-2.0" (at 78.74 115.57 0)
      (effects (font (size 1.27 1.27) (thickness 0.15)) (justify left bottom) hide)
    )
    (property "Author" "Antmicro" (at 76.2 115.57 0)
      (effects (font (size 1.27 1.27) (thickness 0.15)) (justify left bottom) hide)
    )
    (property "Voltage" "" (at 73.66 115.57 0)
      (effects (font (size 1.27 1.27)) (justify left bottom) hide)
    )
    (property "Dielectric" "" (at 71.12 115.57 0)
      (effects (font (size 1.27 1.27)) (justify left bottom) hide)
    )
    (property "Public" "False" (at 68.58 115.57 0)
      (effects (font (size 1.27 1.27)) (justify left bottom) hide)
    )
    (pin "1")
    (pin "2")
    (instances
      (project "ecp5-dc-scm"
        (path ""
          (reference "C163") (unit 1)
        )
      )
    )
  )

  (symbol (lib_id "antmicroCapacitors0402:C_470n_0402") (at 95.25 135.89 270) (mirror x) (unit 1)
    (in_bom yes) (on_board yes) (dnp no)
    (property "Reference" "C166" (at 97.79 135.255 0)
      (effects (font (size 1.524 1.524)) (justify left))
    )
    (property "Value" "C_470n_0402" (at 91.44 135.89 0)
      (effects (font (size 1.524 1.524)) hide)
    )
    (property "Footprint" "antmicro-footprints:C_0402_1005Metric" (at 100.33 130.81 0)
      (effects (font (size 1.524 1.524)) (justify left) hide)
    )
    (property "Datasheet" "https://product.tdk.com/en/search/capacitor/ceramic/mlcc/info?part_no=C1005X5R1E474M050BB" (at 95.25 135.89 0)
      (effects (font (size 1.27 1.27)) hide)
    )
    (property "Manufacturer" "TDK" (at 105.41 130.81 0)
      (effects (font (size 1.524 1.524)) (justify left) hide)
    )
    (property "MPN" "C1005X5R1E474M050BB" (at 102.87 130.81 0)
      (effects (font (size 1.524 1.524)) (justify left) hide)
    )
    (property "Val" "470n" (at 92.71 135.255 0)
      (effects (font (size 1.27 1.27)) (justify left))
    )
    (property "License" "Apache-2.0" (at 72.39 115.57 0)
      (effects (font (size 1.27 1.27) (thickness 0.15)) (justify left bottom) hide)
    )
    (property "Author" "Antmicro" (at 69.85 115.57 0)
      (effects (font (size 1.27 1.27) (thickness 0.15)) (justify left bottom) hide)
    )
    (property "Voltage" "" (at 67.31 115.57 0)
      (effects (font (size 1.27 1.27)) (justify left bottom) hide)
    )
    (property "Dielectric" "" (at 64.77 115.57 0)
      (effects (font (size 1.27 1.27)) (justify left bottom) hide)
    )
    (property "Public" "False" (at 62.23 115.57 0)
      (effects (font (size 1.27 1.27)) (justify left bottom) hide)
    )
    (pin "1")
    (pin "2")
    (instances
      (project "ecp5-dc-scm"
        (path ""
          (reference "C166") (unit 1)
        )
      )
    )
  )

  (symbol (lib_id "antmicroCapacitors0402:C_4u7_0402") (at 77.47 102.87 90) (unit 1)
    (in_bom yes) (on_board yes) (dnp no)
    (property "Reference" "C134" (at 74.93 102.235 0)
      (effects (font (size 1.524 1.524)) (justify left))
    )
    (property "Value" "C_4u7_0402" (at 81.28 102.87 0)
      (effects (font (size 1.524 1.524)) hide)
    )
    (property "Footprint" "antmicro-footprints:C_0402_1005Metric" (at 72.39 97.79 0)
      (effects (font (size 1.524 1.524)) (justify left) hide)
    )
    (property "Datasheet" "https://www.murata.com/products/productdetail?partno=GRM155R61A475MEAA%23" (at 77.47 102.87 0)
      (effects (font (size 1.27 1.27)) hide)
    )
    (property "Manufacturer" "Murata" (at 67.31 97.79 0)
      (effects (font (size 1.524 1.524)) (justify left) hide)
    )
    (property "MPN" "GRM155R61A475MEAAD" (at 69.85 97.79 0)
      (effects (font (size 1.524 1.524)) (justify left) hide)
    )
    (property "Val" "4u7" (at 80.01 102.235 0)
      (effects (font (size 1.27 1.27)) (justify left))
    )
    (property "License" "Apache-2.0" (at 100.33 82.55 0)
      (effects (font (size 1.27 1.27) (thickness 0.15)) (justify left bottom) hide)
    )
    (property "Author" "Antmicro" (at 102.87 82.55 0)
      (effects (font (size 1.27 1.27) (thickness 0.15)) (justify left bottom) hide)
    )
    (property "Voltage" "" (at 105.41 82.55 0)
      (effects (font (size 1.27 1.27)) (justify left bottom) hide)
    )
    (property "Dielectric" "" (at 107.95 82.55 0)
      (effects (font (size 1.27 1.27)) (justify left bottom) hide)
    )
    (property "Public" "False" (at 110.49 82.55 0)
      (effects (font (size 1.27 1.27)) (justify left bottom) hide)
    )
    (pin "1")
    (pin "2")
    (instances
      (project "ecp5-dc-scm"
        (path ""
          (reference "C134") (unit 1)
        )
      )
    )
  )

  (symbol (lib_id "antmicroCapacitors0603:C_47u_0603") (at 71.12 102.87 90) (unit 1)
    (in_bom yes) (on_board yes) (dnp no)
    (property "Reference" "C133" (at 68.58 102.235 0)
      (effects (font (size 1.524 1.524)) (justify left))
    )
    (property "Value" "C_47u_0603" (at 74.93 102.87 0)
      (effects (font (size 1.524 1.524)) hide)
    )
    (property "Footprint" "antmicro-footprints:C_0603_1608Metric" (at 66.04 97.79 0)
      (effects (font (size 1.524 1.524)) (justify left) hide)
    )
    (property "Datasheet" "https://www.murata.com/products/productdetail?partno=GRM188R60J476ME15%23" (at 71.12 102.87 0)
      (effects (font (size 1.27 1.27)) hide)
    )
    (property "Manufacturer" "Murata" (at 60.96 97.79 0)
      (effects (font (size 1.524 1.524)) (justify left) hide)
    )
    (property "MPN" "GRM188R60J476ME15D" (at 63.5 97.79 0)
      (effects (font (size 1.524 1.524)) (justify left) hide)
    )
    (property "Val" "47u" (at 73.66 102.235 0)
      (effects (font (size 1.27 1.27)) (justify left))
    )
    (property "License" "Apache-2.0" (at 93.98 82.55 0)
      (effects (font (size 1.27 1.27) (thickness 0.15)) (justify left bottom) hide)
    )
    (property "Author" "Antmicro" (at 96.52 82.55 0)
      (effects (font (size 1.27 1.27) (thickness 0.15)) (justify left bottom) hide)
    )
    (property "Voltage" "" (at 99.06 82.55 0)
      (effects (font (size 1.27 1.27)) (justify left bottom) hide)
    )
    (property "Dielectric" "" (at 101.6 82.55 0)
      (effects (font (size 1.27 1.27)) (justify left bottom) hide)
    )
    (property "Public" "False" (at 104.14 82.55 0)
      (effects (font (size 1.27 1.27)) (justify left bottom) hide)
    )
    (pin "1")
    (pin "2")
    (instances
      (project "ecp5-dc-scm"
        (path ""
          (reference "C133") (unit 1)
        )
      )
    )
  )

  (symbol (lib_id "antmicroCapacitors0402:C_470n_0402") (at 83.82 102.87 90) (unit 1)
    (in_bom yes) (on_board yes) (dnp no)
    (property "Reference" "C135" (at 81.28 102.235 0)
      (effects (font (size 1.524 1.524)) (justify left))
    )
    (property "Value" "C_470n_0402" (at 87.63 102.87 0)
      (effects (font (size 1.524 1.524)) hide)
    )
    (property "Footprint" "antmicro-footprints:C_0402_1005Metric" (at 78.74 97.79 0)
      (effects (font (size 1.524 1.524)) (justify left) hide)
    )
    (property "Datasheet" "https://product.tdk.com/en/search/capacitor/ceramic/mlcc/info?part_no=C1005X5R1E474M050BB" (at 83.82 102.87 0)
      (effects (font (size 1.27 1.27)) hide)
    )
    (property "Manufacturer" "TDK" (at 73.66 97.79 0)
      (effects (font (size 1.524 1.524)) (justify left) hide)
    )
    (property "MPN" "C1005X5R1E474M050BB" (at 76.2 97.79 0)
      (effects (font (size 1.524 1.524)) (justify left) hide)
    )
    (property "Val" "470n" (at 86.36 102.235 0)
      (effects (font (size 1.27 1.27)) (justify left))
    )
    (property "License" "Apache-2.0" (at 106.68 82.55 0)
      (effects (font (size 1.27 1.27) (thickness 0.15)) (justify left bottom) hide)
    )
    (property "Author" "Antmicro" (at 109.22 82.55 0)
      (effects (font (size 1.27 1.27) (thickness 0.15)) (justify left bottom) hide)
    )
    (property "Voltage" "" (at 111.76 82.55 0)
      (effects (font (size 1.27 1.27)) (justify left bottom) hide)
    )
    (property "Dielectric" "" (at 114.3 82.55 0)
      (effects (font (size 1.27 1.27)) (justify left bottom) hide)
    )
    (property "Public" "False" (at 116.84 82.55 0)
      (effects (font (size 1.27 1.27)) (justify left bottom) hide)
    )
    (pin "1")
    (pin "2")
    (instances
      (project "ecp5-dc-scm"
        (path ""
          (reference "C135") (unit 1)
        )
      )
    )
  )

  (symbol (lib_id "antmicroCapacitors0402:C_470n_0402") (at 90.17 102.87 90) (unit 1)
    (in_bom yes) (on_board yes) (dnp no)
    (property "Reference" "C136" (at 87.63 102.235 0)
      (effects (font (size 1.524 1.524)) (justify left))
    )
    (property "Value" "C_470n_0402" (at 93.98 102.87 0)
      (effects (font (size 1.524 1.524)) hide)
    )
    (property "Footprint" "antmicro-footprints:C_0402_1005Metric" (at 85.09 97.79 0)
      (effects (font (size 1.524 1.524)) (justify left) hide)
    )
    (property "Datasheet" "https://product.tdk.com/en/search/capacitor/ceramic/mlcc/info?part_no=C1005X5R1E474M050BB" (at 90.17 102.87 0)
      (effects (font (size 1.27 1.27)) hide)
    )
    (property "Manufacturer" "TDK" (at 80.01 97.79 0)
      (effects (font (size 1.524 1.524)) (justify left) hide)
    )
    (property "MPN" "C1005X5R1E474M050BB" (at 82.55 97.79 0)
      (effects (font (size 1.524 1.524)) (justify left) hide)
    )
    (property "Val" "470n" (at 92.71 102.235 0)
      (effects (font (size 1.27 1.27)) (justify left))
    )
    (property "License" "Apache-2.0" (at 113.03 82.55 0)
      (effects (font (size 1.27 1.27) (thickness 0.15)) (justify left bottom) hide)
    )
    (property "Author" "Antmicro" (at 115.57 82.55 0)
      (effects (font (size 1.27 1.27) (thickness 0.15)) (justify left bottom) hide)
    )
    (property "Voltage" "" (at 118.11 82.55 0)
      (effects (font (size 1.27 1.27)) (justify left bottom) hide)
    )
    (property "Dielectric" "" (at 120.65 82.55 0)
      (effects (font (size 1.27 1.27)) (justify left bottom) hide)
    )
    (property "Public" "False" (at 123.19 82.55 0)
      (effects (font (size 1.27 1.27)) (justify left bottom) hide)
    )
    (pin "1")
    (pin "2")
    (instances
      (project "ecp5-dc-scm"
        (path ""
          (reference "C136") (unit 1)
        )
      )
    )
  )

  (symbol (lib_id "antmicroCapacitors0402:C_100n_0402") (at 96.52 102.87 90) (unit 1)
    (in_bom yes) (on_board yes) (dnp no)
    (property "Reference" "C137" (at 93.98 102.235 0)
      (effects (font (size 1.524 1.524)) (justify left))
    )
    (property "Value" "C_100n_0402" (at 100.33 102.87 0)
      (effects (font (size 1.524 1.524)) hide)
    )
    (property "Footprint" "antmicro-footprints:C_0402_1005Metric" (at 91.44 97.79 0)
      (effects (font (size 1.524 1.524)) (justify left) hide)
    )
    (property "Datasheet" "https://www.murata.com/products/productdetail?partno=GRM155R61H104KE14%23" (at 96.52 102.87 0)
      (effects (font (size 1.27 1.27)) hide)
    )
    (property "Manufacturer" "Murata" (at 86.36 97.79 0)
      (effects (font (size 1.524 1.524)) (justify left) hide)
    )
    (property "MPN" "GRM155R61H104KE14D" (at 88.9 97.79 0)
      (effects (font (size 1.524 1.524)) (justify left) hide)
    )
    (property "Val" "100n" (at 99.06 102.235 0)
      (effects (font (size 1.27 1.27)) (justify left))
    )
    (property "License" "Apache-2.0" (at 119.38 82.55 0)
      (effects (font (size 1.27 1.27) (thickness 0.15)) (justify left bottom) hide)
    )
    (property "Author" "Antmicro" (at 121.92 82.55 0)
      (effects (font (size 1.27 1.27) (thickness 0.15)) (justify left bottom) hide)
    )
    (property "Voltage" "50V" (at 124.46 82.55 0)
      (effects (font (size 1.27 1.27)) (justify left bottom) hide)
    )
    (property "Dielectric" "X5R" (at 127 82.55 0)
      (effects (font (size 1.27 1.27)) (justify left bottom) hide)
    )
    (property "Public" "False" (at 129.54 82.55 0)
      (effects (font (size 1.27 1.27)) (justify left bottom) hide)
    )
    (pin "1")
    (pin "2")
    (instances
      (project "ecp5-dc-scm"
        (path ""
          (reference "C137") (unit 1)
        )
      )
    )
  )

  (symbol (lib_id "antmicroCapacitors0402:C_10n_0402") (at 102.87 102.87 90) (unit 1)
    (in_bom yes) (on_board yes) (dnp no)
    (property "Reference" "C138" (at 100.33 102.235 0)
      (effects (font (size 1.524 1.524)) (justify left))
    )
    (property "Value" "C_10n_0402" (at 106.68 102.87 0)
      (effects (font (size 1.524 1.524)) hide)
    )
    (property "Footprint" "antmicro-footprints:C_0402_1005Metric" (at 97.79 97.79 0)
      (effects (font (size 1.524 1.524)) (justify left) hide)
    )
    (property "Datasheet" "https://www.murata.com/products/productdetail?partno=GRM155R71H103KA88%23" (at 102.87 102.87 0)
      (effects (font (size 1.27 1.27)) hide)
    )
    (property "Manufacturer" "Murata" (at 92.71 97.79 0)
      (effects (font (size 1.524 1.524)) (justify left) hide)
    )
    (property "MPN" "GRM155R71H103KA88D" (at 95.25 97.79 0)
      (effects (font (size 1.524 1.524)) (justify left) hide)
    )
    (property "Val" "10n" (at 105.41 102.235 0)
      (effects (font (size 1.27 1.27)) (justify left))
    )
    (property "License" "Apache-2.0" (at 125.73 82.55 0)
      (effects (font (size 1.27 1.27) (thickness 0.15)) (justify left bottom) hide)
    )
    (property "Author" "Antmicro" (at 128.27 82.55 0)
      (effects (font (size 1.27 1.27) (thickness 0.15)) (justify left bottom) hide)
    )
    (property "Voltage" "50V" (at 130.81 82.55 0)
      (effects (font (size 1.27 1.27)) (justify left bottom) hide)
    )
    (property "Dielectric" "X7R" (at 133.35 82.55 0)
      (effects (font (size 1.27 1.27)) (justify left bottom) hide)
    )
    (property "Public" "False" (at 135.89 82.55 0)
      (effects (font (size 1.27 1.27)) (justify left bottom) hide)
    )
    (pin "1")
    (pin "2")
    (instances
      (project "ecp5-dc-scm"
        (path ""
          (reference "C138") (unit 1)
        )
      )
    )
  )

  (symbol (lib_id "antmicroCapacitors0402:C_1n_0402") (at 115.57 102.87 90) (unit 1)
    (in_bom yes) (on_board yes) (dnp no)
    (property "Reference" "C148" (at 113.03 102.235 0)
      (effects (font (size 1.524 1.524)) (justify left))
    )
    (property "Value" "C_1n_0402" (at 119.38 102.87 0)
      (effects (font (size 1.524 1.524)) hide)
    )
    (property "Footprint" "antmicro-footprints:C_0402_1005Metric" (at 110.49 97.79 0)
      (effects (font (size 1.524 1.524)) (justify left) hide)
    )
    (property "Datasheet" "https://www.murata.com/products/productdetail?partno=GRM1555C1H102JA01%23" (at 115.57 102.87 0)
      (effects (font (size 1.27 1.27)) hide)
    )
    (property "Manufacturer" "Murata" (at 105.41 97.79 0)
      (effects (font (size 1.524 1.524)) (justify left) hide)
    )
    (property "MPN" "GRM1555C1H102JA01D" (at 107.95 97.79 0)
      (effects (font (size 1.524 1.524)) (justify left) hide)
    )
    (property "Val" "1n" (at 118.11 102.235 0)
      (effects (font (size 1.27 1.27)) (justify left))
    )
    (property "License" "Apache-2.0" (at 138.43 82.55 0)
      (effects (font (size 1.27 1.27) (thickness 0.15)) (justify left bottom) hide)
    )
    (property "Author" "Antmicro" (at 140.97 82.55 0)
      (effects (font (size 1.27 1.27) (thickness 0.15)) (justify left bottom) hide)
    )
    (property "Voltage" "50V" (at 143.51 82.55 0)
      (effects (font (size 1.27 1.27)) (justify left bottom) hide)
    )
    (property "Dielectric" "C0G" (at 146.05 82.55 0)
      (effects (font (size 1.27 1.27)) (justify left bottom) hide)
    )
    (property "Public" "False" (at 148.59 82.55 0)
      (effects (font (size 1.27 1.27)) (justify left bottom) hide)
    )
    (pin "1")
    (pin "2")
    (instances
      (project "ecp5-dc-scm"
        (path ""
          (reference "C148") (unit 1)
        )
      )
    )
  )

  (symbol (lib_id "antmicroCapacitors0402:C_10n_0402") (at 109.22 102.87 90) (unit 1)
    (in_bom yes) (on_board yes) (dnp no)
    (property "Reference" "C143" (at 106.68 102.235 0)
      (effects (font (size 1.524 1.524)) (justify left))
    )
    (property "Value" "C_10n_0402" (at 113.03 102.87 0)
      (effects (font (size 1.524 1.524)) hide)
    )
    (property "Footprint" "antmicro-footprints:C_0402_1005Metric" (at 104.14 97.79 0)
      (effects (font (size 1.524 1.524)) (justify left) hide)
    )
    (property "Datasheet" "https://www.murata.com/products/productdetail?partno=GRM155R71H103KA88%23" (at 109.22 102.87 0)
      (effects (font (size 1.27 1.27)) hide)
    )
    (property "Manufacturer" "Murata" (at 99.06 97.79 0)
      (effects (font (size 1.524 1.524)) (justify left) hide)
    )
    (property "MPN" "GRM155R71H103KA88D" (at 101.6 97.79 0)
      (effects (font (size 1.524 1.524)) (justify left) hide)
    )
    (property "Val" "10n" (at 111.76 102.235 0)
      (effects (font (size 1.27 1.27)) (justify left))
    )
    (property "License" "Apache-2.0" (at 132.08 82.55 0)
      (effects (font (size 1.27 1.27) (thickness 0.15)) (justify left bottom) hide)
    )
    (property "Author" "Antmicro" (at 134.62 82.55 0)
      (effects (font (size 1.27 1.27) (thickness 0.15)) (justify left bottom) hide)
    )
    (property "Voltage" "50V" (at 137.16 82.55 0)
      (effects (font (size 1.27 1.27)) (justify left bottom) hide)
    )
    (property "Dielectric" "X7R" (at 139.7 82.55 0)
      (effects (font (size 1.27 1.27)) (justify left bottom) hide)
    )
    (property "Public" "False" (at 142.24 82.55 0)
      (effects (font (size 1.27 1.27)) (justify left bottom) hide)
    )
    (pin "1")
    (pin "2")
    (instances
      (project "ecp5-dc-scm"
        (path ""
          (reference "C143") (unit 1)
        )
      )
    )
  )

  (symbol (lib_id "antmicroCapacitors0402:C_100n_0402") (at 88.9 135.89 270) (mirror x) (unit 1)
    (in_bom yes) (on_board yes) (dnp no)
    (property "Reference" "C169" (at 91.44 135.255 0)
      (effects (font (size 1.524 1.524)) (justify left))
    )
    (property "Value" "C_100n_0402" (at 85.09 135.89 0)
      (effects (font (size 1.524 1.524)) hide)
    )
    (property "Footprint" "antmicro-footprints:C_0402_1005Metric" (at 93.98 130.81 0)
      (effects (font (size 1.524 1.524)) (justify left) hide)
    )
    (property "Datasheet" "https://www.murata.com/products/productdetail?partno=GRM155R61H104KE14%23" (at 88.9 135.89 0)
      (effects (font (size 1.27 1.27)) hide)
    )
    (property "Manufacturer" "Murata" (at 99.06 130.81 0)
      (effects (font (size 1.524 1.524)) (justify left) hide)
    )
    (property "MPN" "GRM155R61H104KE14D" (at 96.52 130.81 0)
      (effects (font (size 1.524 1.524)) (justify left) hide)
    )
    (property "Val" "100n" (at 86.36 135.255 0)
      (effects (font (size 1.27 1.27)) (justify left))
    )
    (property "License" "Apache-2.0" (at 66.04 115.57 0)
      (effects (font (size 1.27 1.27) (thickness 0.15)) (justify left bottom) hide)
    )
    (property "Author" "Antmicro" (at 63.5 115.57 0)
      (effects (font (size 1.27 1.27) (thickness 0.15)) (justify left bottom) hide)
    )
    (property "Voltage" "50V" (at 60.96 115.57 0)
      (effects (font (size 1.27 1.27)) (justify left bottom) hide)
    )
    (property "Dielectric" "X5R" (at 58.42 115.57 0)
      (effects (font (size 1.27 1.27)) (justify left bottom) hide)
    )
    (property "Public" "False" (at 55.88 115.57 0)
      (effects (font (size 1.27 1.27)) (justify left bottom) hide)
    )
    (pin "1")
    (pin "2")
    (instances
      (project "ecp5-dc-scm"
        (path ""
          (reference "C169") (unit 1)
        )
      )
    )
  )

  (symbol (lib_id "antmicroCapacitors0402:C_10n_0402") (at 82.55 135.89 270) (mirror x) (unit 1)
    (in_bom yes) (on_board yes) (dnp no)
    (property "Reference" "C172" (at 85.09 135.255 0)
      (effects (font (size 1.524 1.524)) (justify left))
    )
    (property "Value" "C_10n_0402" (at 78.74 135.89 0)
      (effects (font (size 1.524 1.524)) hide)
    )
    (property "Footprint" "antmicro-footprints:C_0402_1005Metric" (at 87.63 130.81 0)
      (effects (font (size 1.524 1.524)) (justify left) hide)
    )
    (property "Datasheet" "https://www.murata.com/products/productdetail?partno=GRM155R71H103KA88%23" (at 82.55 135.89 0)
      (effects (font (size 1.27 1.27)) hide)
    )
    (property "Manufacturer" "Murata" (at 92.71 130.81 0)
      (effects (font (size 1.524 1.524)) (justify left) hide)
    )
    (property "MPN" "GRM155R71H103KA88D" (at 90.17 130.81 0)
      (effects (font (size 1.524 1.524)) (justify left) hide)
    )
    (property "Val" "10n" (at 80.01 135.255 0)
      (effects (font (size 1.27 1.27)) (justify left))
    )
    (property "License" "Apache-2.0" (at 59.69 115.57 0)
      (effects (font (size 1.27 1.27) (thickness 0.15)) (justify left bottom) hide)
    )
    (property "Author" "Antmicro" (at 57.15 115.57 0)
      (effects (font (size 1.27 1.27) (thickness 0.15)) (justify left bottom) hide)
    )
    (property "Voltage" "50V" (at 54.61 115.57 0)
      (effects (font (size 1.27 1.27)) (justify left bottom) hide)
    )
    (property "Dielectric" "X7R" (at 52.07 115.57 0)
      (effects (font (size 1.27 1.27)) (justify left bottom) hide)
    )
    (property "Public" "False" (at 49.53 115.57 0)
      (effects (font (size 1.27 1.27)) (justify left bottom) hide)
    )
    (pin "1")
    (pin "2")
    (instances
      (project "ecp5-dc-scm"
        (path ""
          (reference "C172") (unit 1)
        )
      )
    )
  )

  (symbol (lib_id "antmicroCapacitors0402:C_1n_0402") (at 69.85 135.89 270) (mirror x) (unit 1)
    (in_bom yes) (on_board yes) (dnp no)
    (property "Reference" "C178" (at 72.39 135.255 0)
      (effects (font (size 1.524 1.524)) (justify left))
    )
    (property "Value" "C_1n_0402" (at 66.04 135.89 0)
      (effects (font (size 1.524 1.524)) hide)
    )
    (property "Footprint" "antmicro-footprints:C_0402_1005Metric" (at 74.93 130.81 0)
      (effects (font (size 1.524 1.524)) (justify left) hide)
    )
    (property "Datasheet" "https://www.murata.com/products/productdetail?partno=GRM1555C1H102JA01%23" (at 69.85 135.89 0)
      (effects (font (size 1.27 1.27)) hide)
    )
    (property "Manufacturer" "Murata" (at 80.01 130.81 0)
      (effects (font (size 1.524 1.524)) (justify left) hide)
    )
    (property "MPN" "GRM1555C1H102JA01D" (at 77.47 130.81 0)
      (effects (font (size 1.524 1.524)) (justify left) hide)
    )
    (property "Val" "1n" (at 67.31 135.255 0)
      (effects (font (size 1.27 1.27)) (justify left))
    )
    (property "License" "Apache-2.0" (at 46.99 115.57 0)
      (effects (font (size 1.27 1.27) (thickness 0.15)) (justify left bottom) hide)
    )
    (property "Author" "Antmicro" (at 44.45 115.57 0)
      (effects (font (size 1.27 1.27) (thickness 0.15)) (justify left bottom) hide)
    )
    (property "Voltage" "50V" (at 41.91 115.57 0)
      (effects (font (size 1.27 1.27)) (justify left bottom) hide)
    )
    (property "Dielectric" "C0G" (at 39.37 115.57 0)
      (effects (font (size 1.27 1.27)) (justify left bottom) hide)
    )
    (property "Public" "False" (at 36.83 115.57 0)
      (effects (font (size 1.27 1.27)) (justify left bottom) hide)
    )
    (pin "1")
    (pin "2")
    (instances
      (project "ecp5-dc-scm"
        (path ""
          (reference "C178") (unit 1)
        )
      )
    )
  )

  (symbol (lib_id "antmicroCapacitors0402:C_10n_0402") (at 76.2 135.89 270) (mirror x) (unit 1)
    (in_bom yes) (on_board yes) (dnp no)
    (property "Reference" "C175" (at 78.74 135.255 0)
      (effects (font (size 1.524 1.524)) (justify left))
    )
    (property "Value" "C_10n_0402" (at 72.39 135.89 0)
      (effects (font (size 1.524 1.524)) hide)
    )
    (property "Footprint" "antmicro-footprints:C_0402_1005Metric" (at 81.28 130.81 0)
      (effects (font (size 1.524 1.524)) (justify left) hide)
    )
    (property "Datasheet" "https://www.murata.com/products/productdetail?partno=GRM155R71H103KA88%23" (at 76.2 135.89 0)
      (effects (font (size 1.27 1.27)) hide)
    )
    (property "Manufacturer" "Murata" (at 86.36 130.81 0)
      (effects (font (size 1.524 1.524)) (justify left) hide)
    )
    (property "MPN" "GRM155R71H103KA88D" (at 83.82 130.81 0)
      (effects (font (size 1.524 1.524)) (justify left) hide)
    )
    (property "Val" "10n" (at 73.66 135.255 0)
      (effects (font (size 1.27 1.27)) (justify left))
    )
    (property "License" "Apache-2.0" (at 53.34 115.57 0)
      (effects (font (size 1.27 1.27) (thickness 0.15)) (justify left bottom) hide)
    )
    (property "Author" "Antmicro" (at 50.8 115.57 0)
      (effects (font (size 1.27 1.27) (thickness 0.15)) (justify left bottom) hide)
    )
    (property "Voltage" "50V" (at 48.26 115.57 0)
      (effects (font (size 1.27 1.27)) (justify left bottom) hide)
    )
    (property "Dielectric" "X7R" (at 45.72 115.57 0)
      (effects (font (size 1.27 1.27)) (justify left bottom) hide)
    )
    (property "Public" "False" (at 43.18 115.57 0)
      (effects (font (size 1.27 1.27)) (justify left bottom) hide)
    )
    (pin "1")
    (pin "2")
    (instances
      (project "ecp5-dc-scm"
        (path ""
          (reference "C175") (unit 1)
        )
      )
    )
  )

  (symbol (lib_id "antmicroCapacitors0402:C_100n_0402") (at 323.85 153.67 270) (mirror x) (unit 1)
    (in_bom yes) (on_board yes) (dnp no)
    (property "Reference" "C142" (at 326.39 153.035 0)
      (effects (font (size 1.524 1.524)) (justify left))
    )
    (property "Value" "C_100n_0402" (at 320.04 153.67 0)
      (effects (font (size 1.524 1.524)) hide)
    )
    (property "Footprint" "antmicro-footprints:C_0402_1005Metric" (at 328.93 148.59 0)
      (effects (font (size 1.524 1.524)) (justify left) hide)
    )
    (property "Datasheet" "https://www.murata.com/products/productdetail?partno=GRM155R61H104KE14%23" (at 323.85 153.67 0)
      (effects (font (size 1.27 1.27)) hide)
    )
    (property "Manufacturer" "Murata" (at 334.01 148.59 0)
      (effects (font (size 1.524 1.524)) (justify left) hide)
    )
    (property "MPN" "GRM155R61H104KE14D" (at 331.47 148.59 0)
      (effects (font (size 1.524 1.524)) (justify left) hide)
    )
    (property "Val" "100n" (at 321.31 153.035 0)
      (effects (font (size 1.27 1.27)) (justify left))
    )
    (property "License" "Apache-2.0" (at 300.99 133.35 0)
      (effects (font (size 1.27 1.27) (thickness 0.15)) (justify left bottom) hide)
    )
    (property "Author" "Antmicro" (at 298.45 133.35 0)
      (effects (font (size 1.27 1.27) (thickness 0.15)) (justify left bottom) hide)
    )
    (property "Voltage" "50V" (at 295.91 133.35 0)
      (effects (font (size 1.27 1.27)) (justify left bottom) hide)
    )
    (property "Dielectric" "X5R" (at 293.37 133.35 0)
      (effects (font (size 1.27 1.27)) (justify left bottom) hide)
    )
    (property "Public" "False" (at 290.83 133.35 0)
      (effects (font (size 1.27 1.27)) (justify left bottom) hide)
    )
    (pin "1")
    (pin "2")
    (instances
      (project "ecp5-dc-scm"
        (path ""
          (reference "C142") (unit 1)
        )
      )
    )
  )

  (symbol (lib_id "antmicroCapacitors0402:C_100n_0402") (at 332.74 101.6 270) (mirror x) (unit 1)
    (in_bom yes) (on_board yes) (dnp no)
    (property "Reference" "C140" (at 335.28 100.965 0)
      (effects (font (size 1.524 1.524)) (justify left))
    )
    (property "Value" "C_100n_0402" (at 328.93 101.6 0)
      (effects (font (size 1.524 1.524)) hide)
    )
    (property "Footprint" "antmicro-footprints:C_0402_1005Metric" (at 337.82 96.52 0)
      (effects (font (size 1.524 1.524)) (justify left) hide)
    )
    (property "Datasheet" "https://www.murata.com/products/productdetail?partno=GRM155R61H104KE14%23" (at 332.74 101.6 0)
      (effects (font (size 1.27 1.27)) hide)
    )
    (property "Manufacturer" "Murata" (at 342.9 96.52 0)
      (effects (font (size 1.524 1.524)) (justify left) hide)
    )
    (property "MPN" "GRM155R61H104KE14D" (at 340.36 96.52 0)
      (effects (font (size 1.524 1.524)) (justify left) hide)
    )
    (property "Val" "100n" (at 330.2 100.965 0)
      (effects (font (size 1.27 1.27)) (justify left))
    )
    (property "License" "Apache-2.0" (at 309.88 81.28 0)
      (effects (font (size 1.27 1.27) (thickness 0.15)) (justify left bottom) hide)
    )
    (property "Author" "Antmicro" (at 307.34 81.28 0)
      (effects (font (size 1.27 1.27) (thickness 0.15)) (justify left bottom) hide)
    )
    (property "Voltage" "50V" (at 304.8 81.28 0)
      (effects (font (size 1.27 1.27)) (justify left bottom) hide)
    )
    (property "Dielectric" "X5R" (at 302.26 81.28 0)
      (effects (font (size 1.27 1.27)) (justify left bottom) hide)
    )
    (property "Public" "False" (at 299.72 81.28 0)
      (effects (font (size 1.27 1.27)) (justify left bottom) hide)
    )
    (pin "1")
    (pin "2")
    (instances
      (project "ecp5-dc-scm"
        (path ""
          (reference "C140") (unit 1)
        )
      )
    )
  )

  (symbol (lib_id "antmicroCapacitors0402:C_1n_0402") (at 316.23 78.74 270) (mirror x) (unit 1)
    (in_bom yes) (on_board yes) (dnp no)
    (property "Reference" "C149" (at 318.77 78.105 0)
      (effects (font (size 1.524 1.524)) (justify left))
    )
    (property "Value" "C_1n_0402" (at 312.42 78.74 0)
      (effects (font (size 1.524 1.524)) hide)
    )
    (property "Footprint" "antmicro-footprints:C_0402_1005Metric" (at 321.31 73.66 0)
      (effects (font (size 1.524 1.524)) (justify left) hide)
    )
    (property "Datasheet" "https://www.murata.com/products/productdetail?partno=GRM1555C1H102JA01%23" (at 316.23 78.74 0)
      (effects (font (size 1.27 1.27)) hide)
    )
    (property "Manufacturer" "Murata" (at 326.39 73.66 0)
      (effects (font (size 1.524 1.524)) (justify left) hide)
    )
    (property "MPN" "GRM1555C1H102JA01D" (at 323.85 73.66 0)
      (effects (font (size 1.524 1.524)) (justify left) hide)
    )
    (property "Val" "1n" (at 313.69 78.105 0)
      (effects (font (size 1.27 1.27)) (justify left))
    )
    (property "License" "Apache-2.0" (at 293.37 58.42 0)
      (effects (font (size 1.27 1.27) (thickness 0.15)) (justify left bottom) hide)
    )
    (property "Author" "Antmicro" (at 290.83 58.42 0)
      (effects (font (size 1.27 1.27) (thickness 0.15)) (justify left bottom) hide)
    )
    (property "Voltage" "50V" (at 288.29 58.42 0)
      (effects (font (size 1.27 1.27)) (justify left bottom) hide)
    )
    (property "Dielectric" "C0G" (at 285.75 58.42 0)
      (effects (font (size 1.27 1.27)) (justify left bottom) hide)
    )
    (property "Public" "False" (at 283.21 58.42 0)
      (effects (font (size 1.27 1.27)) (justify left bottom) hide)
    )
    (pin "1")
    (pin "2")
    (instances
      (project "ecp5-dc-scm"
        (path ""
          (reference "C149") (unit 1)
        )
      )
    )
  )

  (symbol (lib_id "antmicroCapacitors0402:C_10n_0402") (at 325.12 78.74 270) (mirror x) (unit 1)
    (in_bom yes) (on_board yes) (dnp no)
    (property "Reference" "C144" (at 327.66 78.105 0)
      (effects (font (size 1.524 1.524)) (justify left))
    )
    (property "Value" "C_10n_0402" (at 321.31 78.74 0)
      (effects (font (size 1.524 1.524)) hide)
    )
    (property "Footprint" "antmicro-footprints:C_0402_1005Metric" (at 330.2 73.66 0)
      (effects (font (size 1.524 1.524)) (justify left) hide)
    )
    (property "Datasheet" "https://www.murata.com/products/productdetail?partno=GRM155R71H103KA88%23" (at 325.12 78.74 0)
      (effects (font (size 1.27 1.27)) hide)
    )
    (property "Manufacturer" "Murata" (at 335.28 73.66 0)
      (effects (font (size 1.524 1.524)) (justify left) hide)
    )
    (property "MPN" "GRM155R71H103KA88D" (at 332.74 73.66 0)
      (effects (font (size 1.524 1.524)) (justify left) hide)
    )
    (property "Val" "10n" (at 322.58 78.105 0)
      (effects (font (size 1.27 1.27)) (justify left))
    )
    (property "License" "Apache-2.0" (at 302.26 58.42 0)
      (effects (font (size 1.27 1.27) (thickness 0.15)) (justify left bottom) hide)
    )
    (property "Author" "Antmicro" (at 299.72 58.42 0)
      (effects (font (size 1.27 1.27) (thickness 0.15)) (justify left bottom) hide)
    )
    (property "Voltage" "50V" (at 297.18 58.42 0)
      (effects (font (size 1.27 1.27)) (justify left bottom) hide)
    )
    (property "Dielectric" "X7R" (at 294.64 58.42 0)
      (effects (font (size 1.27 1.27)) (justify left bottom) hide)
    )
    (property "Public" "False" (at 292.1 58.42 0)
      (effects (font (size 1.27 1.27)) (justify left bottom) hide)
    )
    (pin "1")
    (pin "2")
    (instances
      (project "ecp5-dc-scm"
        (path ""
          (reference "C144") (unit 1)
        )
      )
    )
  )

  (symbol (lib_id "antmicroCapacitors0402:C_100n_0402") (at 332.74 78.74 270) (mirror x) (unit 1)
    (in_bom yes) (on_board yes) (dnp no)
    (property "Reference" "C139" (at 335.28 78.105 0)
      (effects (font (size 1.524 1.524)) (justify left))
    )
    (property "Value" "C_100n_0402" (at 328.93 78.74 0)
      (effects (font (size 1.524 1.524)) hide)
    )
    (property "Footprint" "antmicro-footprints:C_0402_1005Metric" (at 337.82 73.66 0)
      (effects (font (size 1.524 1.524)) (justify left) hide)
    )
    (property "Datasheet" "https://www.murata.com/products/productdetail?partno=GRM155R61H104KE14%23" (at 332.74 78.74 0)
      (effects (font (size 1.27 1.27)) hide)
    )
    (property "Manufacturer" "Murata" (at 342.9 73.66 0)
      (effects (font (size 1.524 1.524)) (justify left) hide)
    )
    (property "MPN" "GRM155R61H104KE14D" (at 340.36 73.66 0)
      (effects (font (size 1.524 1.524)) (justify left) hide)
    )
    (property "Val" "100n" (at 330.2 78.105 0)
      (effects (font (size 1.27 1.27)) (justify left))
    )
    (property "License" "Apache-2.0" (at 309.88 58.42 0)
      (effects (font (size 1.27 1.27) (thickness 0.15)) (justify left bottom) hide)
    )
    (property "Author" "Antmicro" (at 307.34 58.42 0)
      (effects (font (size 1.27 1.27) (thickness 0.15)) (justify left bottom) hide)
    )
    (property "Voltage" "50V" (at 304.8 58.42 0)
      (effects (font (size 1.27 1.27)) (justify left bottom) hide)
    )
    (property "Dielectric" "X5R" (at 302.26 58.42 0)
      (effects (font (size 1.27 1.27)) (justify left bottom) hide)
    )
    (property "Public" "False" (at 299.72 58.42 0)
      (effects (font (size 1.27 1.27)) (justify left bottom) hide)
    )
    (pin "1")
    (pin "2")
    (instances
      (project "ecp5-dc-scm"
        (path ""
          (reference "C139") (unit 1)
        )
      )
    )
  )

  (symbol (lib_id "antmicroCapacitors0402:C_1n_0402") (at 318.77 101.6 270) (mirror x) (unit 1)
    (in_bom yes) (on_board yes) (dnp no)
    (property "Reference" "C150" (at 321.31 100.965 0)
      (effects (font (size 1.524 1.524)) (justify left))
    )
    (property "Value" "C_1n_0402" (at 314.96 101.6 0)
      (effects (font (size 1.524 1.524)) hide)
    )
    (property "Footprint" "antmicro-footprints:C_0402_1005Metric" (at 323.85 96.52 0)
      (effects (font (size 1.524 1.524)) (justify left) hide)
    )
    (property "Datasheet" "https://www.murata.com/products/productdetail?partno=GRM1555C1H102JA01%23" (at 318.77 101.6 0)
      (effects (font (size 1.27 1.27)) hide)
    )
    (property "Manufacturer" "Murata" (at 328.93 96.52 0)
      (effects (font (size 1.524 1.524)) (justify left) hide)
    )
    (property "MPN" "GRM1555C1H102JA01D" (at 326.39 96.52 0)
      (effects (font (size 1.524 1.524)) (justify left) hide)
    )
    (property "Val" "1n" (at 316.23 100.965 0)
      (effects (font (size 1.27 1.27)) (justify left))
    )
    (property "License" "Apache-2.0" (at 295.91 81.28 0)
      (effects (font (size 1.27 1.27) (thickness 0.15)) (justify left bottom) hide)
    )
    (property "Author" "Antmicro" (at 293.37 81.28 0)
      (effects (font (size 1.27 1.27) (thickness 0.15)) (justify left bottom) hide)
    )
    (property "Voltage" "50V" (at 290.83 81.28 0)
      (effects (font (size 1.27 1.27)) (justify left bottom) hide)
    )
    (property "Dielectric" "C0G" (at 288.29 81.28 0)
      (effects (font (size 1.27 1.27)) (justify left bottom) hide)
    )
    (property "Public" "False" (at 285.75 81.28 0)
      (effects (font (size 1.27 1.27)) (justify left bottom) hide)
    )
    (pin "1")
    (pin "2")
    (instances
      (project "ecp5-dc-scm"
        (path ""
          (reference "C150") (unit 1)
        )
      )
    )
  )

  (symbol (lib_id "antmicroCapacitors0402:C_10n_0402") (at 326.39 101.6 270) (mirror x) (unit 1)
    (in_bom yes) (on_board yes) (dnp no)
    (property "Reference" "C145" (at 328.93 100.965 0)
      (effects (font (size 1.524 1.524)) (justify left))
    )
    (property "Value" "C_10n_0402" (at 322.58 101.6 0)
      (effects (font (size 1.524 1.524)) hide)
    )
    (property "Footprint" "antmicro-footprints:C_0402_1005Metric" (at 331.47 96.52 0)
      (effects (font (size 1.524 1.524)) (justify left) hide)
    )
    (property "Datasheet" "https://www.murata.com/products/productdetail?partno=GRM155R71H103KA88%23" (at 326.39 101.6 0)
      (effects (font (size 1.27 1.27)) hide)
    )
    (property "Manufacturer" "Murata" (at 336.55 96.52 0)
      (effects (font (size 1.524 1.524)) (justify left) hide)
    )
    (property "MPN" "GRM155R71H103KA88D" (at 334.01 96.52 0)
      (effects (font (size 1.524 1.524)) (justify left) hide)
    )
    (property "Val" "10n" (at 323.85 100.965 0)
      (effects (font (size 1.27 1.27)) (justify left))
    )
    (property "License" "Apache-2.0" (at 303.53 81.28 0)
      (effects (font (size 1.27 1.27) (thickness 0.15)) (justify left bottom) hide)
    )
    (property "Author" "Antmicro" (at 300.99 81.28 0)
      (effects (font (size 1.27 1.27) (thickness 0.15)) (justify left bottom) hide)
    )
    (property "Voltage" "50V" (at 298.45 81.28 0)
      (effects (font (size 1.27 1.27)) (justify left bottom) hide)
    )
    (property "Dielectric" "X7R" (at 295.91 81.28 0)
      (effects (font (size 1.27 1.27)) (justify left bottom) hide)
    )
    (property "Public" "False" (at 293.37 81.28 0)
      (effects (font (size 1.27 1.27)) (justify left bottom) hide)
    )
    (pin "1")
    (pin "2")
    (instances
      (project "ecp5-dc-scm"
        (path ""
          (reference "C145") (unit 1)
        )
      )
    )
  )

  (symbol (lib_id "antmicroCapacitors0402:C_1n_0402") (at 309.88 153.67 270) (mirror x) (unit 1)
    (in_bom yes) (on_board yes) (dnp no)
    (property "Reference" "C152" (at 312.42 153.035 0)
      (effects (font (size 1.524 1.524)) (justify left))
    )
    (property "Value" "C_1n_0402" (at 306.07 153.67 0)
      (effects (font (size 1.524 1.524)) hide)
    )
    (property "Footprint" "antmicro-footprints:C_0402_1005Metric" (at 314.96 148.59 0)
      (effects (font (size 1.524 1.524)) (justify left) hide)
    )
    (property "Datasheet" "https://www.murata.com/products/productdetail?partno=GRM1555C1H102JA01%23" (at 309.88 153.67 0)
      (effects (font (size 1.27 1.27)) hide)
    )
    (property "Manufacturer" "Murata" (at 320.04 148.59 0)
      (effects (font (size 1.524 1.524)) (justify left) hide)
    )
    (property "MPN" "GRM1555C1H102JA01D" (at 317.5 148.59 0)
      (effects (font (size 1.524 1.524)) (justify left) hide)
    )
    (property "Val" "1n" (at 307.34 153.035 0)
      (effects (font (size 1.27 1.27)) (justify left))
    )
    (property "License" "Apache-2.0" (at 287.02 133.35 0)
      (effects (font (size 1.27 1.27) (thickness 0.15)) (justify left bottom) hide)
    )
    (property "Author" "Antmicro" (at 284.48 133.35 0)
      (effects (font (size 1.27 1.27) (thickness 0.15)) (justify left bottom) hide)
    )
    (property "Voltage" "50V" (at 281.94 133.35 0)
      (effects (font (size 1.27 1.27)) (justify left bottom) hide)
    )
    (property "Dielectric" "C0G" (at 279.4 133.35 0)
      (effects (font (size 1.27 1.27)) (justify left bottom) hide)
    )
    (property "Public" "False" (at 276.86 133.35 0)
      (effects (font (size 1.27 1.27)) (justify left bottom) hide)
    )
    (pin "1")
    (pin "2")
    (instances
      (project "ecp5-dc-scm"
        (path ""
          (reference "C152") (unit 1)
        )
      )
    )
  )

  (symbol (lib_id "antmicroCapacitors0402:C_10n_0402") (at 317.5 153.67 270) (mirror x) (unit 1)
    (in_bom yes) (on_board yes) (dnp no)
    (property "Reference" "C147" (at 320.04 153.035 0)
      (effects (font (size 1.524 1.524)) (justify left))
    )
    (property "Value" "C_10n_0402" (at 313.69 153.67 0)
      (effects (font (size 1.524 1.524)) hide)
    )
    (property "Footprint" "antmicro-footprints:C_0402_1005Metric" (at 322.58 148.59 0)
      (effects (font (size 1.524 1.524)) (justify left) hide)
    )
    (property "Datasheet" "https://www.murata.com/products/productdetail?partno=GRM155R71H103KA88%23" (at 317.5 153.67 0)
      (effects (font (size 1.27 1.27)) hide)
    )
    (property "Manufacturer" "Murata" (at 327.66 148.59 0)
      (effects (font (size 1.524 1.524)) (justify left) hide)
    )
    (property "MPN" "GRM155R71H103KA88D" (at 325.12 148.59 0)
      (effects (font (size 1.524 1.524)) (justify left) hide)
    )
    (property "Val" "10n" (at 314.96 153.035 0)
      (effects (font (size 1.27 1.27)) (justify left))
    )
    (property "License" "Apache-2.0" (at 294.64 133.35 0)
      (effects (font (size 1.27 1.27) (thickness 0.15)) (justify left bottom) hide)
    )
    (property "Author" "Antmicro" (at 292.1 133.35 0)
      (effects (font (size 1.27 1.27) (thickness 0.15)) (justify left bottom) hide)
    )
    (property "Voltage" "50V" (at 289.56 133.35 0)
      (effects (font (size 1.27 1.27)) (justify left bottom) hide)
    )
    (property "Dielectric" "X7R" (at 287.02 133.35 0)
      (effects (font (size 1.27 1.27)) (justify left bottom) hide)
    )
    (property "Public" "False" (at 284.48 133.35 0)
      (effects (font (size 1.27 1.27)) (justify left bottom) hide)
    )
    (pin "1")
    (pin "2")
    (instances
      (project "ecp5-dc-scm"
        (path ""
          (reference "C147") (unit 1)
        )
      )
    )
  )

  (symbol (lib_id "antmicroCapacitors0402:C_1n_0402") (at 312.42 127 270) (mirror x) (unit 1)
    (in_bom yes) (on_board yes) (dnp no)
    (property "Reference" "C151" (at 314.96 126.365 0)
      (effects (font (size 1.524 1.524)) (justify left))
    )
    (property "Value" "C_1n_0402" (at 308.61 127 0)
      (effects (font (size 1.524 1.524)) hide)
    )
    (property "Footprint" "antmicro-footprints:C_0402_1005Metric" (at 317.5 121.92 0)
      (effects (font (size 1.524 1.524)) (justify left) hide)
    )
    (property "Datasheet" "https://www.murata.com/products/productdetail?partno=GRM1555C1H102JA01%23" (at 312.42 127 0)
      (effects (font (size 1.27 1.27)) hide)
    )
    (property "Manufacturer" "Murata" (at 322.58 121.92 0)
      (effects (font (size 1.524 1.524)) (justify left) hide)
    )
    (property "MPN" "GRM1555C1H102JA01D" (at 320.04 121.92 0)
      (effects (font (size 1.524 1.524)) (justify left) hide)
    )
    (property "Val" "1n" (at 309.88 126.365 0)
      (effects (font (size 1.27 1.27)) (justify left))
    )
    (property "License" "Apache-2.0" (at 289.56 106.68 0)
      (effects (font (size 1.27 1.27) (thickness 0.15)) (justify left bottom) hide)
    )
    (property "Author" "Antmicro" (at 287.02 106.68 0)
      (effects (font (size 1.27 1.27) (thickness 0.15)) (justify left bottom) hide)
    )
    (property "Voltage" "50V" (at 284.48 106.68 0)
      (effects (font (size 1.27 1.27)) (justify left bottom) hide)
    )
    (property "Dielectric" "C0G" (at 281.94 106.68 0)
      (effects (font (size 1.27 1.27)) (justify left bottom) hide)
    )
    (property "Public" "False" (at 279.4 106.68 0)
      (effects (font (size 1.27 1.27)) (justify left bottom) hide)
    )
    (pin "1")
    (pin "2")
    (instances
      (project "ecp5-dc-scm"
        (path ""
          (reference "C151") (unit 1)
        )
      )
    )
  )

  (symbol (lib_id "antmicroCapacitors0402:C_10n_0402") (at 320.04 127 270) (mirror x) (unit 1)
    (in_bom yes) (on_board yes) (dnp no)
    (property "Reference" "C146" (at 322.58 126.365 0)
      (effects (font (size 1.524 1.524)) (justify left))
    )
    (property "Value" "C_10n_0402" (at 316.23 127 0)
      (effects (font (size 1.524 1.524)) hide)
    )
    (property "Footprint" "antmicro-footprints:C_0402_1005Metric" (at 325.12 121.92 0)
      (effects (font (size 1.524 1.524)) (justify left) hide)
    )
    (property "Datasheet" "https://www.murata.com/products/productdetail?partno=GRM155R71H103KA88%23" (at 320.04 127 0)
      (effects (font (size 1.27 1.27)) hide)
    )
    (property "Manufacturer" "Murata" (at 330.2 121.92 0)
      (effects (font (size 1.524 1.524)) (justify left) hide)
    )
    (property "MPN" "GRM155R71H103KA88D" (at 327.66 121.92 0)
      (effects (font (size 1.524 1.524)) (justify left) hide)
    )
    (property "Val" "10n" (at 317.5 126.365 0)
      (effects (font (size 1.27 1.27)) (justify left))
    )
    (property "License" "Apache-2.0" (at 297.18 106.68 0)
      (effects (font (size 1.27 1.27) (thickness 0.15)) (justify left bottom) hide)
    )
    (property "Author" "Antmicro" (at 294.64 106.68 0)
      (effects (font (size 1.27 1.27) (thickness 0.15)) (justify left bottom) hide)
    )
    (property "Voltage" "50V" (at 292.1 106.68 0)
      (effects (font (size 1.27 1.27)) (justify left bottom) hide)
    )
    (property "Dielectric" "X7R" (at 289.56 106.68 0)
      (effects (font (size 1.27 1.27)) (justify left bottom) hide)
    )
    (property "Public" "False" (at 287.02 106.68 0)
      (effects (font (size 1.27 1.27)) (justify left bottom) hide)
    )
    (pin "1")
    (pin "2")
    (instances
      (project "ecp5-dc-scm"
        (path ""
          (reference "C146") (unit 1)
        )
      )
    )
  )

  (symbol (lib_id "antmicroCapacitors0402:C_100n_0402") (at 327.66 127 270) (mirror x) (unit 1)
    (in_bom yes) (on_board yes) (dnp no)
    (property "Reference" "C141" (at 330.2 126.365 0)
      (effects (font (size 1.524 1.524)) (justify left))
    )
    (property "Value" "C_100n_0402" (at 323.85 127 0)
      (effects (font (size 1.524 1.524)) hide)
    )
    (property "Footprint" "antmicro-footprints:C_0402_1005Metric" (at 332.74 121.92 0)
      (effects (font (size 1.524 1.524)) (justify left) hide)
    )
    (property "Datasheet" "https://www.murata.com/products/productdetail?partno=GRM155R61H104KE14%23" (at 327.66 127 0)
      (effects (font (size 1.27 1.27)) hide)
    )
    (property "Manufacturer" "Murata" (at 337.82 121.92 0)
      (effects (font (size 1.524 1.524)) (justify left) hide)
    )
    (property "MPN" "GRM155R61H104KE14D" (at 335.28 121.92 0)
      (effects (font (size 1.524 1.524)) (justify left) hide)
    )
    (property "Val" "100n" (at 325.12 126.365 0)
      (effects (font (size 1.27 1.27)) (justify left))
    )
    (property "License" "Apache-2.0" (at 304.8 106.68 0)
      (effects (font (size 1.27 1.27) (thickness 0.15)) (justify left bottom) hide)
    )
    (property "Author" "Antmicro" (at 302.26 106.68 0)
      (effects (font (size 1.27 1.27) (thickness 0.15)) (justify left bottom) hide)
    )
    (property "Voltage" "50V" (at 299.72 106.68 0)
      (effects (font (size 1.27 1.27)) (justify left bottom) hide)
    )
    (property "Dielectric" "X5R" (at 297.18 106.68 0)
      (effects (font (size 1.27 1.27)) (justify left bottom) hide)
    )
    (property "Public" "False" (at 294.64 106.68 0)
      (effects (font (size 1.27 1.27)) (justify left bottom) hide)
    )
    (pin "1")
    (pin "2")
    (instances
      (project "ecp5-dc-scm"
        (path ""
          (reference "C141") (unit 1)
        )
      )
    )
  )

  (symbol (lib_id "antmicroCapacitors0402:C_470n_0402") (at 151.13 68.58 90) (mirror x) (unit 1)
    (in_bom yes) (on_board yes) (dnp no)
    (property "Reference" "C194" (at 151.13 69.85 90)
      (effects (font (size 1.524 1.524)) (justify left))
    )
    (property "Value" "C_470n_0402" (at 154.94 68.58 0)
      (effects (font (size 1.524 1.524)) hide)
    )
    (property "Footprint" "antmicro-footprints:C_0402_1005Metric" (at 146.05 73.66 0)
      (effects (font (size 1.524 1.524)) (justify left) hide)
    )
    (property "Datasheet" "https://product.tdk.com/en/search/capacitor/ceramic/mlcc/info?part_no=C1005X5R1E474M050BB" (at 151.13 68.58 0)
      (effects (font (size 1.27 1.27)) hide)
    )
    (property "Manufacturer" "TDK" (at 140.97 73.66 0)
      (effects (font (size 1.524 1.524)) (justify left) hide)
    )
    (property "MPN" "C1005X5R1E474M050BB" (at 143.51 73.66 0)
      (effects (font (size 1.524 1.524)) (justify left) hide)
    )
    (property "Val" "470n" (at 151.13 73.025 90)
      (effects (font (size 1.27 1.27)) (justify left))
    )
    (property "License" "Apache-2.0" (at 173.99 88.9 0)
      (effects (font (size 1.27 1.27) (thickness 0.15)) (justify left bottom) hide)
    )
    (property "Author" "Antmicro" (at 176.53 88.9 0)
      (effects (font (size 1.27 1.27) (thickness 0.15)) (justify left bottom) hide)
    )
    (property "Voltage" "" (at 179.07 88.9 0)
      (effects (font (size 1.27 1.27)) (justify left bottom) hide)
    )
    (property "Dielectric" "" (at 181.61 88.9 0)
      (effects (font (size 1.27 1.27)) (justify left bottom) hide)
    )
    (property "Public" "False" (at 184.15 88.9 0)
      (effects (font (size 1.27 1.27)) (justify left bottom) hide)
    )
    (pin "1")
    (pin "2")
    (instances
      (project "ecp5-dc-scm"
        (path ""
          (reference "C194") (unit 1)
        )
      )
    )
  )

  (symbol (lib_id "antmicroCapacitors0402:C_470n_0402") (at 157.48 68.58 90) (mirror x) (unit 1)
    (in_bom yes) (on_board yes) (dnp no)
    (property "Reference" "C195" (at 157.48 69.85 90)
      (effects (font (size 1.524 1.524)) (justify left))
    )
    (property "Value" "C_470n_0402" (at 161.29 68.58 0)
      (effects (font (size 1.524 1.524)) hide)
    )
    (property "Footprint" "antmicro-footprints:C_0402_1005Metric" (at 152.4 73.66 0)
      (effects (font (size 1.524 1.524)) (justify left) hide)
    )
    (property "Datasheet" "https://product.tdk.com/en/search/capacitor/ceramic/mlcc/info?part_no=C1005X5R1E474M050BB" (at 157.48 68.58 0)
      (effects (font (size 1.27 1.27)) hide)
    )
    (property "Manufacturer" "TDK" (at 147.32 73.66 0)
      (effects (font (size 1.524 1.524)) (justify left) hide)
    )
    (property "MPN" "C1005X5R1E474M050BB" (at 149.86 73.66 0)
      (effects (font (size 1.524 1.524)) (justify left) hide)
    )
    (property "Val" "470n" (at 157.48 73.025 90)
      (effects (font (size 1.27 1.27)) (justify left))
    )
    (property "License" "Apache-2.0" (at 180.34 88.9 0)
      (effects (font (size 1.27 1.27) (thickness 0.15)) (justify left bottom) hide)
    )
    (property "Author" "Antmicro" (at 182.88 88.9 0)
      (effects (font (size 1.27 1.27) (thickness 0.15)) (justify left bottom) hide)
    )
    (property "Voltage" "" (at 185.42 88.9 0)
      (effects (font (size 1.27 1.27)) (justify left bottom) hide)
    )
    (property "Dielectric" "" (at 187.96 88.9 0)
      (effects (font (size 1.27 1.27)) (justify left bottom) hide)
    )
    (property "Public" "False" (at 190.5 88.9 0)
      (effects (font (size 1.27 1.27)) (justify left bottom) hide)
    )
    (pin "1")
    (pin "2")
    (instances
      (project "ecp5-dc-scm"
        (path ""
          (reference "C195") (unit 1)
        )
      )
    )
  )

  (symbol (lib_id "antmicroCapacitors0402:C_1n_0402") (at 63.5 135.89 270) (mirror x) (unit 1)
    (in_bom yes) (on_board yes) (dnp no)
    (property "Reference" "C180" (at 66.04 135.255 0)
      (effects (font (size 1.524 1.524)) (justify left))
    )
    (property "Value" "C_1n_0402" (at 59.69 135.89 0)
      (effects (font (size 1.524 1.524)) hide)
    )
    (property "Footprint" "antmicro-footprints:C_0402_1005Metric" (at 68.58 130.81 0)
      (effects (font (size 1.524 1.524)) (justify left) hide)
    )
    (property "Datasheet" "https://www.murata.com/products/productdetail?partno=GRM1555C1H102JA01%23" (at 63.5 135.89 0)
      (effects (font (size 1.27 1.27)) hide)
    )
    (property "Manufacturer" "Murata" (at 73.66 130.81 0)
      (effects (font (size 1.524 1.524)) (justify left) hide)
    )
    (property "MPN" "GRM1555C1H102JA01D" (at 71.12 130.81 0)
      (effects (font (size 1.524 1.524)) (justify left) hide)
    )
    (property "Val" "1n" (at 60.96 135.255 0)
      (effects (font (size 1.27 1.27)) (justify left))
    )
    (property "License" "Apache-2.0" (at 40.64 115.57 0)
      (effects (font (size 1.27 1.27) (thickness 0.15)) (justify left bottom) hide)
    )
    (property "Author" "Antmicro" (at 38.1 115.57 0)
      (effects (font (size 1.27 1.27) (thickness 0.15)) (justify left bottom) hide)
    )
    (property "Voltage" "50V" (at 35.56 115.57 0)
      (effects (font (size 1.27 1.27)) (justify left bottom) hide)
    )
    (property "Dielectric" "C0G" (at 33.02 115.57 0)
      (effects (font (size 1.27 1.27)) (justify left bottom) hide)
    )
    (property "Public" "False" (at 30.48 115.57 0)
      (effects (font (size 1.27 1.27)) (justify left bottom) hide)
    )
    (pin "1")
    (pin "2")
    (instances
      (project "ecp5-dc-scm"
        (path ""
          (reference "C180") (unit 1)
        )
      )
    )
  )

  (symbol (lib_id "antmicroCapacitors0402:C_1n_0402") (at 121.92 102.87 270) (mirror x) (unit 1)
    (in_bom yes) (on_board yes) (dnp no)
    (property "Reference" "C153" (at 124.46 102.235 0)
      (effects (font (size 1.524 1.524)) (justify left))
    )
    (property "Value" "C_1n_0402" (at 118.11 102.87 0)
      (effects (font (size 1.524 1.524)) hide)
    )
    (property "Footprint" "antmicro-footprints:C_0402_1005Metric" (at 127 97.79 0)
      (effects (font (size 1.524 1.524)) (justify left) hide)
    )
    (property "Datasheet" "https://www.murata.com/products/productdetail?partno=GRM1555C1H102JA01%23" (at 121.92 102.87 0)
      (effects (font (size 1.27 1.27)) hide)
    )
    (property "Manufacturer" "Murata" (at 132.08 97.79 0)
      (effects (font (size 1.524 1.524)) (justify left) hide)
    )
    (property "MPN" "GRM1555C1H102JA01D" (at 129.54 97.79 0)
      (effects (font (size 1.524 1.524)) (justify left) hide)
    )
    (property "Val" "1n" (at 119.38 102.235 0)
      (effects (font (size 1.27 1.27)) (justify left))
    )
    (property "License" "Apache-2.0" (at 99.06 82.55 0)
      (effects (font (size 1.27 1.27) (thickness 0.15)) (justify left bottom) hide)
    )
    (property "Author" "Antmicro" (at 96.52 82.55 0)
      (effects (font (size 1.27 1.27) (thickness 0.15)) (justify left bottom) hide)
    )
    (property "Voltage" "50V" (at 93.98 82.55 0)
      (effects (font (size 1.27 1.27)) (justify left bottom) hide)
    )
    (property "Dielectric" "C0G" (at 91.44 82.55 0)
      (effects (font (size 1.27 1.27)) (justify left bottom) hide)
    )
    (property "Public" "False" (at 88.9 82.55 0)
      (effects (font (size 1.27 1.27)) (justify left bottom) hide)
    )
    (pin "1")
    (pin "2")
    (instances
      (project "ecp5-dc-scm"
        (path ""
          (reference "C153") (unit 1)
        )
      )
    )
  )

  (symbol (lib_id "antmicropower:GND") (at 332.74 105.41 0) (mirror y) (unit 1)
    (in_bom yes) (on_board yes) (dnp no)
    (property "Reference" "#PWR097" (at 332.74 111.76 0)
      (effects (font (size 1.27 1.27)) hide)
    )
    (property "Value" "GND" (at 332.613 109.8042 0)
      (effects (font (size 1.27 1.27)))
    )
    (property "Footprint" "" (at 332.74 105.41 0)
      (effects (font (size 1.27 1.27)) hide)
    )
    (property "Datasheet" "" (at 332.74 105.41 0)
      (effects (font (size 1.27 1.27)) hide)
    )
    (property "Author" "Antmicro" (at 323.85 113.03 0)
      (effects (font (size 1.27 1.27) (thickness 0.15)) (justify left bottom) hide)
    )
    (property "License" "Apache-2.0" (at 323.85 115.57 0)
      (effects (font (size 1.27 1.27) (thickness 0.15)) (justify left bottom) hide)
    )
    (pin "1")
    (instances
      (project "ecp5-dc-scm"
        (path ""
          (reference "#PWR097") (unit 1)
        )
      )
    )
  )

  (symbol (lib_id "antmicropower:GND") (at 327.66 132.08 0) (mirror y) (unit 1)
    (in_bom yes) (on_board yes) (dnp no)
    (property "Reference" "#PWR096" (at 327.66 138.43 0)
      (effects (font (size 1.27 1.27)) hide)
    )
    (property "Value" "GND" (at 327.533 136.4742 0)
      (effects (font (size 1.27 1.27)))
    )
    (property "Footprint" "" (at 327.66 132.08 0)
      (effects (font (size 1.27 1.27)) hide)
    )
    (property "Datasheet" "" (at 327.66 132.08 0)
      (effects (font (size 1.27 1.27)) hide)
    )
    (property "Author" "Antmicro" (at 318.77 139.7 0)
      (effects (font (size 1.27 1.27) (thickness 0.15)) (justify left bottom) hide)
    )
    (property "License" "Apache-2.0" (at 318.77 142.24 0)
      (effects (font (size 1.27 1.27) (thickness 0.15)) (justify left bottom) hide)
    )
    (pin "1")
    (instances
      (project "ecp5-dc-scm"
        (path ""
          (reference "#PWR096") (unit 1)
        )
      )
    )
  )

  (symbol (lib_id "antmicropower:GND") (at 64.77 107.95 0) (unit 1)
    (in_bom yes) (on_board yes) (dnp no)
    (property "Reference" "#PWR094" (at 64.77 114.3 0)
      (effects (font (size 1.27 1.27)) hide)
    )
    (property "Value" "GND" (at 64.897 112.3442 0)
      (effects (font (size 1.27 1.27)))
    )
    (property "Footprint" "" (at 64.77 107.95 0)
      (effects (font (size 1.27 1.27)) hide)
    )
    (property "Datasheet" "" (at 64.77 107.95 0)
      (effects (font (size 1.27 1.27)) hide)
    )
    (property "Author" "Antmicro" (at 73.66 115.57 0)
      (effects (font (size 1.27 1.27) (thickness 0.15)) (justify left bottom) hide)
    )
    (property "License" "Apache-2.0" (at 73.66 118.11 0)
      (effects (font (size 1.27 1.27) (thickness 0.15)) (justify left bottom) hide)
    )
    (pin "1")
    (instances
      (project "ecp5-dc-scm"
        (path ""
          (reference "#PWR094") (unit 1)
        )
      )
    )
  )

  (symbol (lib_id "antmicropower:GND") (at 332.74 82.55 0) (mirror y) (unit 1)
    (in_bom yes) (on_board yes) (dnp no)
    (property "Reference" "#PWR095" (at 332.74 88.9 0)
      (effects (font (size 1.27 1.27)) hide)
    )
    (property "Value" "GND" (at 332.613 86.9442 0)
      (effects (font (size 1.27 1.27)))
    )
    (property "Footprint" "" (at 332.74 82.55 0)
      (effects (font (size 1.27 1.27)) hide)
    )
    (property "Datasheet" "" (at 332.74 82.55 0)
      (effects (font (size 1.27 1.27)) hide)
    )
    (property "Author" "Antmicro" (at 323.85 90.17 0)
      (effects (font (size 1.27 1.27) (thickness 0.15)) (justify left bottom) hide)
    )
    (property "License" "Apache-2.0" (at 323.85 92.71 0)
      (effects (font (size 1.27 1.27) (thickness 0.15)) (justify left bottom) hide)
    )
    (pin "1")
    (instances
      (project "ecp5-dc-scm"
        (path ""
          (reference "#PWR095") (unit 1)
        )
      )
    )
  )

  (symbol (lib_id "antmicropower:GND") (at 323.85 157.48 0) (mirror y) (unit 1)
    (in_bom yes) (on_board yes) (dnp no)
    (property "Reference" "#PWR098" (at 323.85 163.83 0)
      (effects (font (size 1.27 1.27)) hide)
    )
    (property "Value" "GND" (at 323.723 161.8742 0)
      (effects (font (size 1.27 1.27)))
    )
    (property "Footprint" "" (at 323.85 157.48 0)
      (effects (font (size 1.27 1.27)) hide)
    )
    (property "Datasheet" "" (at 323.85 157.48 0)
      (effects (font (size 1.27 1.27)) hide)
    )
    (property "Author" "Antmicro" (at 314.96 165.1 0)
      (effects (font (size 1.27 1.27) (thickness 0.15)) (justify left bottom) hide)
    )
    (property "License" "Apache-2.0" (at 314.96 167.64 0)
      (effects (font (size 1.27 1.27) (thickness 0.15)) (justify left bottom) hide)
    )
    (pin "1")
    (instances
      (project "ecp5-dc-scm"
        (path ""
          (reference "#PWR098") (unit 1)
        )
      )
    )
  )

  (symbol (lib_id "antmicropower:GND") (at 63.5 140.97 0) (mirror y) (unit 1)
    (in_bom yes) (on_board yes) (dnp no)
    (property "Reference" "#PWR0100" (at 63.5 147.32 0)
      (effects (font (size 1.27 1.27)) hide)
    )
    (property "Value" "GND" (at 63.373 145.3642 0)
      (effects (font (size 1.27 1.27)))
    )
    (property "Footprint" "" (at 63.5 140.97 0)
      (effects (font (size 1.27 1.27)) hide)
    )
    (property "Datasheet" "" (at 63.5 140.97 0)
      (effects (font (size 1.27 1.27)) hide)
    )
    (property "Author" "Antmicro" (at 54.61 148.59 0)
      (effects (font (size 1.27 1.27) (thickness 0.15)) (justify left bottom) hide)
    )
    (property "License" "Apache-2.0" (at 54.61 151.13 0)
      (effects (font (size 1.27 1.27) (thickness 0.15)) (justify left bottom) hide)
    )
    (pin "1")
    (instances
      (project "ecp5-dc-scm"
        (path ""
          (reference "#PWR0100") (unit 1)
        )
      )
    )
  )

  (symbol (lib_id "antmicropower:GND") (at 30.48 77.47 0) (mirror y) (unit 1)
    (in_bom yes) (on_board yes) (dnp no)
    (property "Reference" "#PWR0102" (at 30.48 83.82 0)
      (effects (font (size 1.27 1.27)) hide)
    )
    (property "Value" "GND" (at 30.353 81.8642 0)
      (effects (font (size 1.27 1.27)))
    )
    (property "Footprint" "" (at 30.48 77.47 0)
      (effects (font (size 1.27 1.27)) hide)
    )
    (property "Datasheet" "" (at 30.48 77.47 0)
      (effects (font (size 1.27 1.27)) hide)
    )
    (property "Author" "Antmicro" (at 21.59 85.09 0)
      (effects (font (size 1.27 1.27) (thickness 0.15)) (justify left bottom) hide)
    )
    (property "License" "Apache-2.0" (at 21.59 87.63 0)
      (effects (font (size 1.27 1.27) (thickness 0.15)) (justify left bottom) hide)
    )
    (pin "1")
    (instances
      (project "ecp5-dc-scm"
        (path ""
          (reference "#PWR0102") (unit 1)
        )
      )
    )
  )

  (symbol (lib_id "antmicropower:GND") (at 62.23 176.53 0) (mirror y) (unit 1)
    (in_bom yes) (on_board yes) (dnp no)
    (property "Reference" "#PWR0101" (at 62.23 182.88 0)
      (effects (font (size 1.27 1.27)) hide)
    )
    (property "Value" "GND" (at 62.103 180.9242 0)
      (effects (font (size 1.27 1.27)))
    )
    (property "Footprint" "" (at 62.23 176.53 0)
      (effects (font (size 1.27 1.27)) hide)
    )
    (property "Datasheet" "" (at 62.23 176.53 0)
      (effects (font (size 1.27 1.27)) hide)
    )
    (property "Author" "Antmicro" (at 53.34 184.15 0)
      (effects (font (size 1.27 1.27) (thickness 0.15)) (justify left bottom) hide)
    )
    (property "License" "Apache-2.0" (at 53.34 186.69 0)
      (effects (font (size 1.27 1.27) (thickness 0.15)) (justify left bottom) hide)
    )
    (pin "1")
    (instances
      (project "ecp5-dc-scm"
        (path ""
          (reference "#PWR0101") (unit 1)
        )
      )
    )
  )

  (symbol (lib_id "antmicroFerriteBeadsandChips:FB_120Z_2A_Murata-BLM18PG_0603") (at 41.91 165.1 0) (mirror y) (unit 1)
    (in_bom yes) (on_board yes) (dnp no) (fields_autoplaced)
    (property "Reference" "FB8" (at 39.4081 156.21 0)
      (effects (font (size 1.524 1.524)))
    )
    (property "Value" "FB_120Z_2A_Murata-BLM18PG_0603" (at 39.4081 158.75 0)
      (effects (font (size 1.524 1.524)))
    )
    (property "Footprint" "antmicro-footprints:FB_0603_1608Metric" (at 36.83 160.02 0)
      (effects (font (size 1.524 1.524)) (justify left) hide)
    )
    (property "Datasheet" "https://www.murata.com/en-us/products/productdata/8796738650142/ENFA0003.pdf" (at 36.83 157.48 0)
      (effects (font (size 1.524 1.524)) (justify left) hide)
    )
    (property "MPN" "BLM18PG121SN1D" (at 36.83 152.4 0)
      (effects (font (size 1.524 1.524)) (justify left) hide)
    )
    (property "Manufacturer" "Murata" (at 36.83 137.16 0)
      (effects (font (size 1.524 1.524)) (justify left) hide)
    )
    (property "Val" "120Z/2A" (at 39.4081 161.29 0)
      (effects (font (size 1.27 1.27)))
    )
    (property "Current" "" (at 21.59 187.96 0)
      (effects (font (size 1.27 1.27) (thickness 0.15)) (justify left bottom) hide)
    )
    (property "Author" "Antmicro" (at 26.67 182.88 0)
      (effects (font (size 1.27 1.27) (thickness 0.15)) (justify left bottom) hide)
    )
    (property "License" "Apache-2.0" (at 26.67 185.42 0)
      (effects (font (size 1.27 1.27) (thickness 0.15)) (justify left bottom) hide)
    )
    (property "Public" "False" (at 21.59 180.34 0)
      (effects (font (size 1.27 1.27)) (justify left bottom) hide)
    )
    (pin "1")
    (pin "2")
    (instances
      (project "ecp5-dc-scm"
        (path ""
          (reference "FB8") (unit 1)
        )
      )
    )
  )

  (symbol (lib_id "antmicroFerriteBeadsandChips:FB_120Z_2A_Murata-BLM18PG_0603") (at 358.14 72.39 0) (mirror y) (unit 1)
    (in_bom yes) (on_board yes) (dnp no) (fields_autoplaced)
    (property "Reference" "FB5" (at 355.6381 63.5 0)
      (effects (font (size 1.524 1.524)))
    )
    (property "Value" "FB_120Z_2A_Murata-BLM18PG_0603" (at 355.6381 66.04 0)
      (effects (font (size 1.524 1.524)))
    )
    (property "Footprint" "antmicro-footprints:FB_0603_1608Metric" (at 353.06 67.31 0)
      (effects (font (size 1.524 1.524)) (justify left) hide)
    )
    (property "Datasheet" "https://www.murata.com/en-us/products/productdata/8796738650142/ENFA0003.pdf" (at 353.06 64.77 0)
      (effects (font (size 1.524 1.524)) (justify left) hide)
    )
    (property "MPN" "BLM18PG121SN1D" (at 353.06 59.69 0)
      (effects (font (size 1.524 1.524)) (justify left) hide)
    )
    (property "Manufacturer" "Murata" (at 353.06 44.45 0)
      (effects (font (size 1.524 1.524)) (justify left) hide)
    )
    (property "Val" "120Z/2A" (at 355.6381 68.58 0)
      (effects (font (size 1.27 1.27)))
    )
    (property "Current" "" (at 337.82 95.25 0)
      (effects (font (size 1.27 1.27) (thickness 0.15)) (justify left bottom) hide)
    )
    (property "Author" "Antmicro" (at 342.9 90.17 0)
      (effects (font (size 1.27 1.27) (thickness 0.15)) (justify left bottom) hide)
    )
    (property "License" "Apache-2.0" (at 342.9 92.71 0)
      (effects (font (size 1.27 1.27) (thickness 0.15)) (justify left bottom) hide)
    )
    (property "Public" "False" (at 337.82 87.63 0)
      (effects (font (size 1.27 1.27)) (justify left bottom) hide)
    )
    (pin "1")
    (pin "2")
    (instances
      (project "ecp5-dc-scm"
        (path ""
          (reference "FB5") (unit 1)
        )
      )
    )
  )

  (symbol (lib_id "antmicroFerriteBeadsandChips:FB_120Z_2A_Murata-BLM18PG_0603") (at 360.68 119.38 0) (mirror y) (unit 1)
    (in_bom yes) (on_board yes) (dnp no) (fields_autoplaced)
    (property "Reference" "FB6" (at 358.1781 110.49 0)
      (effects (font (size 1.524 1.524)))
    )
    (property "Value" "FB_120Z_2A_Murata-BLM18PG_0603" (at 358.1781 113.03 0)
      (effects (font (size 1.524 1.524)))
    )
    (property "Footprint" "antmicro-footprints:FB_0603_1608Metric" (at 355.6 114.3 0)
      (effects (font (size 1.524 1.524)) (justify left) hide)
    )
    (property "Datasheet" "https://www.murata.com/en-us/products/productdata/8796738650142/ENFA0003.pdf" (at 355.6 111.76 0)
      (effects (font (size 1.524 1.524)) (justify left) hide)
    )
    (property "MPN" "BLM18PG121SN1D" (at 355.6 106.68 0)
      (effects (font (size 1.524 1.524)) (justify left) hide)
    )
    (property "Manufacturer" "Murata" (at 355.6 91.44 0)
      (effects (font (size 1.524 1.524)) (justify left) hide)
    )
    (property "Val" "120Z/2A" (at 358.1781 115.57 0)
      (effects (font (size 1.27 1.27)))
    )
    (property "Current" "" (at 340.36 142.24 0)
      (effects (font (size 1.27 1.27) (thickness 0.15)) (justify left bottom) hide)
    )
    (property "Author" "Antmicro" (at 345.44 137.16 0)
      (effects (font (size 1.27 1.27) (thickness 0.15)) (justify left bottom) hide)
    )
    (property "License" "Apache-2.0" (at 345.44 139.7 0)
      (effects (font (size 1.27 1.27) (thickness 0.15)) (justify left bottom) hide)
    )
    (property "Public" "False" (at 340.36 134.62 0)
      (effects (font (size 1.27 1.27)) (justify left bottom) hide)
    )
    (pin "1")
    (pin "2")
    (instances
      (project "ecp5-dc-scm"
        (path ""
          (reference "FB6") (unit 1)
        )
      )
    )
  )

  (symbol (lib_id "antmicroFerriteBeadsandChips:FB_120Z_2A_Murata-BLM18PG_0603") (at 52.07 128.27 0) (mirror y) (unit 1)
    (in_bom yes) (on_board yes) (dnp no) (fields_autoplaced)
    (property "Reference" "FB7" (at 49.5681 119.38 0)
      (effects (font (size 1.524 1.524)))
    )
    (property "Value" "FB_120Z_2A_Murata-BLM18PG_0603" (at 49.5681 121.92 0)
      (effects (font (size 1.524 1.524)))
    )
    (property "Footprint" "antmicro-footprints:FB_0603_1608Metric" (at 46.99 123.19 0)
      (effects (font (size 1.524 1.524)) (justify left) hide)
    )
    (property "Datasheet" "https://www.murata.com/en-us/products/productdata/8796738650142/ENFA0003.pdf" (at 46.99 120.65 0)
      (effects (font (size 1.524 1.524)) (justify left) hide)
    )
    (property "MPN" "BLM18PG121SN1D" (at 46.99 115.57 0)
      (effects (font (size 1.524 1.524)) (justify left) hide)
    )
    (property "Manufacturer" "Murata" (at 46.99 100.33 0)
      (effects (font (size 1.524 1.524)) (justify left) hide)
    )
    (property "Val" "120Z/2A" (at 49.5681 124.46 0)
      (effects (font (size 1.27 1.27)))
    )
    (property "Current" "" (at 31.75 151.13 0)
      (effects (font (size 1.27 1.27) (thickness 0.15)) (justify left bottom) hide)
    )
    (property "Author" "Antmicro" (at 36.83 146.05 0)
      (effects (font (size 1.27 1.27) (thickness 0.15)) (justify left bottom) hide)
    )
    (property "License" "Apache-2.0" (at 36.83 148.59 0)
      (effects (font (size 1.27 1.27) (thickness 0.15)) (justify left bottom) hide)
    )
    (property "Public" "False" (at 31.75 143.51 0)
      (effects (font (size 1.27 1.27)) (justify left bottom) hide)
    )
    (pin "1")
    (pin "2")
    (instances
      (project "ecp5-dc-scm"
        (path ""
          (reference "FB7") (unit 1)
        )
      )
    )
  )

  (symbol (lib_id "antmicroFerriteBeadsandChips:FB_120Z_2A_Murata-BLM18PG_0603") (at 36.83 95.25 0) (unit 1)
    (in_bom yes) (on_board yes) (dnp no) (fields_autoplaced)
    (property "Reference" "FB4" (at 39.3319 85.725 0)
      (effects (font (size 1.524 1.524)))
    )
    (property "Value" "FB_120Z_2A_Murata-BLM18PG_0603" (at 39.3319 88.265 0)
      (effects (font (size 1.524 1.524)))
    )
    (property "Footprint" "antmicro-footprints:FB_0603_1608Metric" (at 41.91 90.17 0)
      (effects (font (size 1.524 1.524)) (justify left) hide)
    )
    (property "Datasheet" "https://www.murata.com/en-us/products/productdata/8796738650142/ENFA0003.pdf" (at 41.91 87.63 0)
      (effects (font (size 1.524 1.524)) (justify left) hide)
    )
    (property "MPN" "BLM18PG121SN1D" (at 41.91 82.55 0)
      (effects (font (size 1.524 1.524)) (justify left) hide)
    )
    (property "Manufacturer" "Murata" (at 41.91 67.31 0)
      (effects (font (size 1.524 1.524)) (justify left) hide)
    )
    (property "Val" "120Z/2A" (at 39.3319 90.805 0)
      (effects (font (size 1.27 1.27)))
    )
    (property "Current" "" (at 57.15 118.11 0)
      (effects (font (size 1.27 1.27) (thickness 0.15)) (justify left bottom) hide)
    )
    (property "Author" "Antmicro" (at 52.07 113.03 0)
      (effects (font (size 1.27 1.27) (thickness 0.15)) (justify left bottom) hide)
    )
    (property "License" "Apache-2.0" (at 52.07 115.57 0)
      (effects (font (size 1.27 1.27) (thickness 0.15)) (justify left bottom) hide)
    )
    (property "Public" "False" (at 57.15 110.49 0)
      (effects (font (size 1.27 1.27)) (justify left bottom) hide)
    )
    (pin "1")
    (pin "2")
    (instances
      (project "ecp5-dc-scm"
        (path ""
          (reference "FB4") (unit 1)
        )
      )
    )
  )

  (symbol (lib_id "antmicroFPGAChips:ECP5_LFE5UM5G-85") (at 201.93 76.2 0) (unit 1)
    (in_bom yes) (on_board yes) (dnp no) (fields_autoplaced)
    (property "Reference" "U21" (at 220.98 68.58 0)
      (effects (font (size 1.524 1.524)))
    )
    (property "Value" "ECP5UM5G_85_CABGA756" (at 220.98 71.12 0)
      (effects (font (size 1.524 1.524)))
    )
    (property "Footprint" "antmicro-footprints:BGA-1024-756_27x27mm_Layout32x32_P0.8mm" (at 190.5 16.51 90)
      (effects (font (size 1.27 1.27)) hide)
    )
    (property "Datasheet" "https://www.latticesemi.com/-/media/LatticeSemi/Documents/DataSheets/ECP5/FPGA-DS-02012-2-2-ECP5-ECP5G-Family-Data-Sheet.ashx?document_id=50461" (at 190.5 16.51 90)
      (effects (font (size 1.27 1.27)) hide)
    )
    (property "MPN" "LFE5UM5G-85F-8BG756C" (at 189.23 20.32 90)
      (effects (font (size 1.524 1.524)) (justify right) hide)
    )
    (property "Manufacturer" "Lattice Semiconductor" (at 190.5 16.51 90)
      (effects (font (size 1.27 1.27)) hide)
    )
    (property "Author" "Antmicro" (at 279.4 95.25 0)
      (effects (font (size 1.27 1.27) (thickness 0.15)) (justify left bottom) hide)
    )
    (property "License" "Apache-2.0" (at 279.4 97.79 0)
      (effects (font (size 1.27 1.27) (thickness 0.15)) (justify left bottom) hide)
    )
    (pin "AA11")
    (pin "AA12")
    (pin "AA13")
    (pin "AA14")
    (pin "AA15")
    (pin "AA16")
    (pin "AA17")
    (pin "AA18")
    (pin "AA19")
    (pin "AA20")
    (pin "AA21")
    (pin "AA22")
    (pin "AB11")
    (pin "AB12")
    (pin "AB13")
    (pin "AB14")
    (pin "AB15")
    (pin "AB16")
    (pin "AB17")
    (pin "AB18")
    (pin "AB19")
    (pin "AB20")
    (pin "AB21")
    (pin "AB22")
    (pin "AC11")
    (pin "AC12")
    (pin "AC13")
    (pin "AC14")
    (pin "AC15")
    (pin "AC16")
    (pin "AC17")
    (pin "AC18")
    (pin "AC19")
    (pin "AC20")
    (pin "AC21")
    (pin "AC22")
    (pin "AC29")
    (pin "AC4")
    (pin "AD2")
    (pin "AD28")
    (pin "AD31")
    (pin "AD5")
    (pin "AE26")
    (pin "AE7")
    (pin "AF11")
    (pin "AF12")
    (pin "AF14")
    (pin "AF15")
    (pin "AF16")
    (pin "AF17")
    (pin "AF19")
    (pin "AF20")
    (pin "AF22")
    (pin "AF23")
    (pin "AG11")
    (pin "AG12")
    (pin "AG14")
    (pin "AG15")
    (pin "AG16")
    (pin "AG17")
    (pin "AG19")
    (pin "AG2")
    (pin "AG20")
    (pin "AG22")
    (pin "AG23")
    (pin "AG24")
    (pin "AG31")
    (pin "AG9")
    (pin "AH11")
    (pin "AH12")
    (pin "AH14")
    (pin "AH15")
    (pin "AH16")
    (pin "AH17")
    (pin "AH19")
    (pin "AH2")
    (pin "AH20")
    (pin "AH22")
    (pin "AH23")
    (pin "AH24")
    (pin "AH25")
    (pin "AH26")
    (pin "AH29")
    (pin "AH31")
    (pin "AH5")
    (pin "AH7")
    (pin "AH8")
    (pin "AH9")
    (pin "AJ10")
    (pin "AJ11")
    (pin "AJ12")
    (pin "AJ13")
    (pin "AJ14")
    (pin "AJ15")
    (pin "AJ16")
    (pin "AJ17")
    (pin "AJ18")
    (pin "AJ19")
    (pin "AJ20")
    (pin "AJ21")
    (pin "AJ22")
    (pin "AJ23")
    (pin "AJ24")
    (pin "AJ25")
    (pin "AJ26")
    (pin "AJ7")
    (pin "AJ8")
    (pin "AJ9")
    (pin "AK11")
    (pin "AK14")
    (pin "AK15")
    (pin "AK16")
    (pin "AK17")
    (pin "AK20")
    (pin "AK23")
    (pin "AK24")
    (pin "AK25")
    (pin "AK26")
    (pin "AK7")
    (pin "AK8")
    (pin "AL11")
    (pin "AL12")
    (pin "AL14")
    (pin "AL15")
    (pin "AL17")
    (pin "AL18")
    (pin "AL2")
    (pin "AL20")
    (pin "AL21")
    (pin "AL23")
    (pin "AL24")
    (pin "AL26")
    (pin "AL29")
    (pin "AL31")
    (pin "AL5")
    (pin "AL7")
    (pin "AL8")
    (pin "AL9")
    (pin "AM26")
    (pin "AM7")
    (pin "B13")
    (pin "B15")
    (pin "B18")
    (pin "B2")
    (pin "B20")
    (pin "B24")
    (pin "B28")
    (pin "B31")
    (pin "B5")
    (pin "B9")
    (pin "E13")
    (pin "E15")
    (pin "E18")
    (pin "E2")
    (pin "E20")
    (pin "E24")
    (pin "E26")
    (pin "E28")
    (pin "E31")
    (pin "E5")
    (pin "E7")
    (pin "E9")
    (pin "G10")
    (pin "G11")
    (pin "G14")
    (pin "G15")
    (pin "G16")
    (pin "G17")
    (pin "G18")
    (pin "G19")
    (pin "G22")
    (pin "G23")
    (pin "G24")
    (pin "G9")
    (pin "H29")
    (pin "H4")
    (pin "J2")
    (pin "J28")
    (pin "J31")
    (pin "J5")
    (pin "K10")
    (pin "K11")
    (pin "K13")
    (pin "K20")
    (pin "K22")
    (pin "K23")
    (pin "L10")
    (pin "L11")
    (pin "L12")
    (pin "L13")
    (pin "L14")
    (pin "L15")
    (pin "L16")
    (pin "L17")
    (pin "L18")
    (pin "L19")
    (pin "L20")
    (pin "L21")
    (pin "L22")
    (pin "L23")
    (pin "L28")
    (pin "L5")
    (pin "M11")
    (pin "M12")
    (pin "M13")
    (pin "M14")
    (pin "M15")
    (pin "M16")
    (pin "M17")
    (pin "M18")
    (pin "M19")
    (pin "M20")
    (pin "M21")
    (pin "M22")
    (pin "N10")
    (pin "N11")
    (pin "N12")
    (pin "N13")
    (pin "N14")
    (pin "N15")
    (pin "N16")
    (pin "N17")
    (pin "N18")
    (pin "N19")
    (pin "N2")
    (pin "N20")
    (pin "N21")
    (pin "N22")
    (pin "N23")
    (pin "N28")
    (pin "N31")
    (pin "N5")
    (pin "P11")
    (pin "P12")
    (pin "P13")
    (pin "P14")
    (pin "P15")
    (pin "P16")
    (pin "P17")
    (pin "P18")
    (pin "P19")
    (pin "P20")
    (pin "P21")
    (pin "P22")
    (pin "R11")
    (pin "R12")
    (pin "R13")
    (pin "R14")
    (pin "R15")
    (pin "R16")
    (pin "R17")
    (pin "R18")
    (pin "R19")
    (pin "R2")
    (pin "R20")
    (pin "R21")
    (pin "R22")
    (pin "R28")
    (pin "R31")
    (pin "R5")
    (pin "T11")
    (pin "T12")
    (pin "T13")
    (pin "T14")
    (pin "T15")
    (pin "T16")
    (pin "T17")
    (pin "T18")
    (pin "T19")
    (pin "T20")
    (pin "T21")
    (pin "T22")
    (pin "U11")
    (pin "U12")
    (pin "U13")
    (pin "U14")
    (pin "U15")
    (pin "U16")
    (pin "U17")
    (pin "U18")
    (pin "U19")
    (pin "U20")
    (pin "U21")
    (pin "U22")
    (pin "V11")
    (pin "V12")
    (pin "V13")
    (pin "V14")
    (pin "V15")
    (pin "V16")
    (pin "V17")
    (pin "V18")
    (pin "V19")
    (pin "V2")
    (pin "V20")
    (pin "V21")
    (pin "V22")
    (pin "V28")
    (pin "V3")
    (pin "V30")
    (pin "V31")
    (pin "V5")
    (pin "W11")
    (pin "W12")
    (pin "W13")
    (pin "W14")
    (pin "W15")
    (pin "W16")
    (pin "W17")
    (pin "W18")
    (pin "W19")
    (pin "W20")
    (pin "W21")
    (pin "W22")
    (pin "W27")
    (pin "W6")
    (pin "Y10")
    (pin "Y11")
    (pin "Y12")
    (pin "Y13")
    (pin "Y14")
    (pin "Y15")
    (pin "Y16")
    (pin "Y17")
    (pin "Y18")
    (pin "Y19")
    (pin "Y2")
    (pin "Y20")
    (pin "Y21")
    (pin "Y22")
    (pin "Y23")
    (pin "Y31")
    (pin "A10")
    (pin "A11")
    (pin "A13")
    (pin "A14")
    (pin "A15")
    (pin "A16")
    (pin "A17")
    (pin "A2")
    (pin "A3")
    (pin "A4")
    (pin "A5")
    (pin "A7")
    (pin "A8")
    (pin "A9")
    (pin "B10")
    (pin "B11")
    (pin "B14")
    (pin "B16")
    (pin "B17")
    (pin "B3")
    (pin "B4")
    (pin "B7")
    (pin "B8")
    (pin "C10")
    (pin "C11")
    (pin "C13")
    (pin "C14")
    (pin "C15")
    (pin "C16")
    (pin "C17")
    (pin "C7")
    (pin "C8")
    (pin "C9")
    (pin "D10")
    (pin "D11")
    (pin "D13")
    (pin "D14")
    (pin "D15")
    (pin "D16")
    (pin "D17")
    (pin "D7")
    (pin "D8")
    (pin "D9")
    (pin "E10")
    (pin "E11")
    (pin "E14")
    (pin "E16")
    (pin "E8")
    (pin "F10")
    (pin "F11")
    (pin "F13")
    (pin "F14")
    (pin "F15")
    (pin "F16")
    (pin "F8")
    (pin "F9")
    (pin "K12")
    (pin "K14")
    (pin "K15")
    (pin "K16")
    (pin "A18")
    (pin "A19")
    (pin "A20")
    (pin "A22")
    (pin "A23")
    (pin "A24")
    (pin "A25")
    (pin "A26")
    (pin "A28")
    (pin "A29")
    (pin "A30")
    (pin "A31")
    (pin "B19")
    (pin "B22")
    (pin "B23")
    (pin "B25")
    (pin "B26")
    (pin "B29")
    (pin "B30")
    (pin "C18")
    (pin "C19")
    (pin "C20")
    (pin "C22")
    (pin "C23")
    (pin "C24")
    (pin "C25")
    (pin "C26")
    (pin "D18")
    (pin "D19")
    (pin "D20")
    (pin "D22")
    (pin "D23")
    (pin "D24")
    (pin "D25")
    (pin "D26")
    (pin "E17")
    (pin "E19")
    (pin "E22")
    (pin "E23")
    (pin "E25")
    (pin "F17")
    (pin "F18")
    (pin "F19")
    (pin "F20")
    (pin "F22")
    (pin "F23")
    (pin "F24")
    (pin "F25")
    (pin "K17")
    (pin "K18")
    (pin "K19")
    (pin "K21")
    (pin "B32")
    (pin "C28")
    (pin "C29")
    (pin "C30")
    (pin "C31")
    (pin "C32")
    (pin "D28")
    (pin "D29")
    (pin "D30")
    (pin "D31")
    (pin "D32")
    (pin "E29")
    (pin "E30")
    (pin "E32")
    (pin "F28")
    (pin "F29")
    (pin "F30")
    (pin "F31")
    (pin "F32")
    (pin "H27")
    (pin "H28")
    (pin "H30")
    (pin "H31")
    (pin "H32")
    (pin "J26")
    (pin "J27")
    (pin "J29")
    (pin "J30")
    (pin "J32")
    (pin "K26")
    (pin "K27")
    (pin "K28")
    (pin "K29")
    (pin "K30")
    (pin "K31")
    (pin "K32")
    (pin "L26")
    (pin "L27")
    (pin "L29")
    (pin "L30")
    (pin "L31")
    (pin "L32")
    (pin "M23")
    (pin "N26")
    (pin "N27")
    (pin "N29")
    (pin "N30")
    (pin "P23")
    (pin "P26")
    (pin "P27")
    (pin "R23")
    (pin "T23")
    (pin "AA23")
    (pin "AB26")
    (pin "AB27")
    (pin "AB28")
    (pin "AB29")
    (pin "AB30")
    (pin "AB31")
    (pin "AB32")
    (pin "AC26")
    (pin "AC27")
    (pin "AC28")
    (pin "AC30")
    (pin "AC31")
    (pin "AC32")
    (pin "AD26")
    (pin "AD27")
    (pin "AD29")
    (pin "AD30")
    (pin "AD32")
    (pin "AE27")
    (pin "AE28")
    (pin "AE29")
    (pin "AE30")
    (pin "AE31")
    (pin "AE32")
    (pin "N32")
    (pin "P28")
    (pin "P29")
    (pin "P30")
    (pin "P31")
    (pin "P32")
    (pin "R26")
    (pin "R27")
    (pin "R29")
    (pin "R30")
    (pin "R32")
    (pin "T26")
    (pin "T27")
    (pin "T28")
    (pin "T29")
    (pin "T30")
    (pin "T31")
    (pin "T32")
    (pin "U23")
    (pin "U26")
    (pin "U27")
    (pin "U28")
    (pin "U29")
    (pin "U30")
    (pin "U31")
    (pin "U32")
    (pin "V23")
    (pin "V26")
    (pin "V27")
    (pin "V29")
    (pin "V32")
    (pin "W23")
    (pin "W28")
    (pin "W29")
    (pin "W30")
    (pin "W31")
    (pin "W32")
    (pin "Y26")
    (pin "Y27")
    (pin "Y28")
    (pin "Y29")
    (pin "Y30")
    (pin "Y32")
    (pin "AB23")
    (pin "AC23")
    (pin "AG28")
    (pin "AG29")
    (pin "AG30")
    (pin "AG32")
    (pin "AH28")
    (pin "AH30")
    (pin "AH32")
    (pin "AJ28")
    (pin "AJ29")
    (pin "AJ30")
    (pin "AJ31")
    (pin "AJ32")
    (pin "AK28")
    (pin "AK29")
    (pin "AK30")
    (pin "AK31")
    (pin "AK32")
    (pin "AL28")
    (pin "AL30")
    (pin "AL32")
    (pin "AM28")
    (pin "AM29")
    (pin "AM30")
    (pin "AM31")
    (pin "AA10")
    (pin "AB1")
    (pin "AB2")
    (pin "AB3")
    (pin "AB4")
    (pin "AB5")
    (pin "AB6")
    (pin "AB7")
    (pin "AC1")
    (pin "AC2")
    (pin "AC3")
    (pin "AC5")
    (pin "AC6")
    (pin "AC7")
    (pin "AD1")
    (pin "AD3")
    (pin "AD4")
    (pin "AD6")
    (pin "AD7")
    (pin "AE1")
    (pin "AE2")
    (pin "AE3")
    (pin "AE4")
    (pin "AE5")
    (pin "AE6")
    (pin "N1")
    (pin "P1")
    (pin "P2")
    (pin "P3")
    (pin "P4")
    (pin "P5")
    (pin "R1")
    (pin "R3")
    (pin "R4")
    (pin "R6")
    (pin "R7")
    (pin "T1")
    (pin "T2")
    (pin "T3")
    (pin "T4")
    (pin "T5")
    (pin "T6")
    (pin "T7")
    (pin "U1")
    (pin "U10")
    (pin "U2")
    (pin "U3")
    (pin "U4")
    (pin "U5")
    (pin "U6")
    (pin "U7")
    (pin "V1")
    (pin "V10")
    (pin "V4")
    (pin "V6")
    (pin "V7")
    (pin "W1")
    (pin "W10")
    (pin "W2")
    (pin "W3")
    (pin "W4")
    (pin "W5")
    (pin "Y1")
    (pin "Y3")
    (pin "Y4")
    (pin "Y5")
    (pin "Y6")
    (pin "Y7")
    (pin "B1")
    (pin "C1")
    (pin "C2")
    (pin "C3")
    (pin "C4")
    (pin "C5")
    (pin "D1")
    (pin "D2")
    (pin "D3")
    (pin "D4")
    (pin "D5")
    (pin "E1")
    (pin "E3")
    (pin "E4")
    (pin "F1")
    (pin "F2")
    (pin "F3")
    (pin "F4")
    (pin "F5")
    (pin "H1")
    (pin "H2")
    (pin "H3")
    (pin "H5")
    (pin "H6")
    (pin "J1")
    (pin "J3")
    (pin "J4")
    (pin "J6")
    (pin "J7")
    (pin "K1")
    (pin "K2")
    (pin "K3")
    (pin "K4")
    (pin "K5")
    (pin "K6")
    (pin "K7")
    (pin "L1")
    (pin "L2")
    (pin "L3")
    (pin "L4")
    (pin "L6")
    (pin "L7")
    (pin "M10")
    (pin "N3")
    (pin "N4")
    (pin "N6")
    (pin "N7")
    (pin "P10")
    (pin "P6")
    (pin "P7")
    (pin "R10")
    (pin "T10")
    (pin "AB10")
    (pin "AC10")
    (pin "AG1")
    (pin "AG3")
    (pin "AG4")
    (pin "AH1")
    (pin "AH3")
    (pin "AH4")
    (pin "AJ1")
    (pin "AJ2")
    (pin "AJ3")
    (pin "AJ4")
    (pin "AK1")
    (pin "AK2")
    (pin "AK3")
    (pin "AK4")
    (pin "AL1")
    (pin "AL3")
    (pin "AL4")
    (pin "AM2")
    (pin "AM3")
    (pin "AM4")
    (pin "AG5")
    (pin "AJ5")
    (pin "AK5")
    (pin "AM5")
    (pin "AK10")
    (pin "AK12")
    (pin "AK13")
    (pin "AK9")
    (pin "AM11")
    (pin "AM12")
    (pin "AM14")
    (pin "AM15")
    (pin "AM8")
    (pin "AM9")
    (pin "AK18")
    (pin "AK19")
    (pin "AK21")
    (pin "AK22")
    (pin "AM17")
    (pin "AM18")
    (pin "AM20")
    (pin "AM21")
    (pin "AM23")
    (pin "AM24")
    (instances
      (project "ecp5-dc-scm"
        (path ""
          (reference "U21") (unit 1)
        )
      )
    )
  )

  (symbol (lib_id "antmicropower:PWR_FLAG") (at 323.85 144.78 0) (unit 1)
    (in_bom yes) (on_board yes) (dnp no)
    (property "Reference" "#FLG010" (at 323.85 142.875 0)
      (effects (font (size 1.27 1.27)) hide)
    )
    (property "Value" "PWR_FLAG" (at 323.85 140.97 0)
      (effects (font (size 1.27 1.27)))
    )
    (property "Footprint" "" (at 323.85 144.78 0)
      (effects (font (size 1.27 1.27)) hide)
    )
    (property "Datasheet" "" (at 323.85 144.78 0)
      (effects (font (size 1.27 1.27)) hide)
    )
    (pin "1")
    (instances
      (project "ecp5-dc-scm"
        (path ""
          (reference "#FLG010") (unit 1)
        )
      )
    )
  )

  (symbol (lib_id "antmicropower:PWR_FLAG") (at 332.74 92.71 0) (unit 1)
    (in_bom yes) (on_board yes) (dnp no)
    (property "Reference" "#FLG08" (at 332.74 90.805 0)
      (effects (font (size 1.27 1.27)) hide)
    )
    (property "Value" "PWR_FLAG" (at 332.74 88.9 0)
      (effects (font (size 1.27 1.27)))
    )
    (property "Footprint" "" (at 332.74 92.71 0)
      (effects (font (size 1.27 1.27)) hide)
    )
    (property "Datasheet" "" (at 332.74 92.71 0)
      (effects (font (size 1.27 1.27)) hide)
    )
    (pin "1")
    (instances
      (project "ecp5-dc-scm"
        (path ""
          (reference "#FLG08") (unit 1)
        )
      )
    )
  )

  (symbol (lib_id "antmicropower:PWR_FLAG") (at 332.74 71.12 0) (unit 1)
    (in_bom yes) (on_board yes) (dnp no)
    (property "Reference" "#FLG07" (at 332.74 69.215 0)
      (effects (font (size 1.27 1.27)) hide)
    )
    (property "Value" "PWR_FLAG" (at 327.66 67.31 0)
      (effects (font (size 1.27 1.27)))
    )
    (property "Footprint" "" (at 332.74 71.12 0)
      (effects (font (size 1.27 1.27)) hide)
    )
    (property "Datasheet" "" (at 332.74 71.12 0)
      (effects (font (size 1.27 1.27)) hide)
    )
    (pin "1")
    (instances
      (project "ecp5-dc-scm"
        (path ""
          (reference "#FLG07") (unit 1)
        )
      )
    )
  )

  (symbol (lib_id "antmicropower:GND") (at 242.57 123.19 0) (mirror y) (unit 1)
    (in_bom yes) (on_board yes) (dnp no)
    (property "Reference" "#PWR058" (at 242.57 129.54 0)
      (effects (font (size 1.27 1.27)) hide)
    )
    (property "Value" "GND" (at 242.443 127.5842 0)
      (effects (font (size 1.27 1.27)))
    )
    (property "Footprint" "" (at 242.57 123.19 0)
      (effects (font (size 1.27 1.27)) hide)
    )
    (property "Datasheet" "" (at 242.57 123.19 0)
      (effects (font (size 1.27 1.27)) hide)
    )
    (property "Author" "Antmicro" (at 233.68 130.81 0)
      (effects (font (size 1.27 1.27) (thickness 0.15)) (justify left bottom) hide)
    )
    (property "License" "Apache-2.0" (at 233.68 133.35 0)
      (effects (font (size 1.27 1.27) (thickness 0.15)) (justify left bottom) hide)
    )
    (pin "1")
    (instances
      (project "ecp5-dc-scm"
        (path ""
          (reference "#PWR058") (unit 1)
        )
      )
    )
  )

  (symbol (lib_id "antmicropower:PWR_FLAG") (at 62.23 163.83 0) (unit 1)
    (in_bom yes) (on_board yes) (dnp no)
    (property "Reference" "#FLG06" (at 62.23 161.925 0)
      (effects (font (size 1.27 1.27)) hide)
    )
    (property "Value" "PWR_FLAG" (at 67.31 160.02 0)
      (effects (font (size 1.27 1.27)))
    )
    (property "Footprint" "" (at 62.23 163.83 0)
      (effects (font (size 1.27 1.27)) hide)
    )
    (property "Datasheet" "" (at 62.23 163.83 0)
      (effects (font (size 1.27 1.27)) hide)
    )
    (pin "1")
    (instances
      (project "ecp5-dc-scm"
        (path ""
          (reference "#FLG06") (unit 1)
        )
      )
    )
  )

  (symbol (lib_id "antmicropower:PWR_FLAG") (at 327.66 118.11 0) (unit 1)
    (in_bom yes) (on_board yes) (dnp no)
    (property "Reference" "#FLG09" (at 327.66 116.205 0)
      (effects (font (size 1.27 1.27)) hide)
    )
    (property "Value" "PWR_FLAG" (at 327.66 114.3 0)
      (effects (font (size 1.27 1.27)))
    )
    (property "Footprint" "" (at 327.66 118.11 0)
      (effects (font (size 1.27 1.27)) hide)
    )
    (property "Datasheet" "" (at 327.66 118.11 0)
      (effects (font (size 1.27 1.27)) hide)
    )
    (pin "1")
    (instances
      (project "ecp5-dc-scm"
        (path ""
          (reference "#FLG09") (unit 1)
        )
      )
    )
  )
)
